%FSTAX25Y25*%
%MOIN*%
%SFA1B1*%

%IPPOS*%
%ADD10C,0.008000*%
%ADD14C,0.010000*%
%ADD22C,0.005000*%
%ADD53R,0.028000X0.165000*%
%ADD54R,0.028000X0.126000*%
%ADD64R,0.057090X0.045280*%
%ADD66R,0.025200X0.026770*%
%ADD71R,0.045280X0.057090*%
%ADD72R,0.026770X0.025200*%
%ADD76R,0.082870X0.044090*%
%ADD140C,0.120000*%
%ADD147C,0.020000*%
%ADD152C,0.250000*%
%ADD153C,0.031500*%
%ADD154C,0.065980*%
%ADD155C,0.075000*%
%ADD156C,0.098430*%
%ADD157O,0.196850X0.098430*%
%ADD158O,0.177170X0.088580*%
%ADD159O,0.088580X0.177170*%
%ADD160C,0.112000*%
%ADD161C,0.021660*%
%ADD162C,0.055000*%
%ADD163R,0.055000X0.055000*%
%ADD164C,0.050000*%
%ADD165C,0.016000*%
%ADD166C,0.005000*%
%ADD167R,0.073820X0.067910*%
%LNgrandmaster-1*%
%LPD*%
G36*
X1034Y0933816D02*
X08005D01*
X0800188Y0933754*
X0799923Y0933577*
X0799746Y0933312*
X0799684Y0933*
Y092915*
X079945*
Y092205*
X0799684*
Y0918722*
X079971Y0918591*
X0799728Y0918459*
X0799741Y0918436*
X0799746Y091841*
X079982Y0918299*
X0799887Y0918184*
X0799908Y0918167*
X0799923Y0918145*
X0800056Y0917595*
X0799899Y091739*
X0799541Y0916527*
X0799419Y09156*
X0799541Y0914673*
X0799899Y091381*
X0800056Y0913605*
X0799923Y0913055*
X0799908Y0913033*
X0799887Y0913016*
X079982Y0912901*
X0799746Y091279*
X0799741Y0912764*
X0799728Y0912741*
X079971Y0912609*
X0799684Y0912478*
Y0908722*
X079971Y0908591*
X0799728Y0908459*
X0799741Y0908436*
X0799746Y090841*
X079982Y0908299*
X0799887Y0908184*
X0799908Y0908167*
X0799923Y0908145*
X0800056Y0907596*
X0799899Y090739*
X0799541Y0906527*
X0799419Y09056*
X0799541Y0904673*
X0799899Y090381*
X0800056Y0903605*
X0799923Y0903055*
X0799908Y0903033*
X0799887Y0903016*
X079982Y0902901*
X0799746Y0902791*
X0799741Y0902764*
X0799728Y0902741*
X079971Y0902609*
X0799684Y0902478*
Y0885466*
X0799715Y0885313*
X0799745Y0885159*
X0799746Y0885157*
Y0885154*
X0799834Y0885024*
X079992Y0884893*
X0799922Y0884892*
X0799923Y088489*
X0800054Y0884802*
X0800184Y0884715*
X0800486Y0884588*
X0800369Y0884*
X0800383Y0883927*
X0800325Y0883832*
X079995Y0883542*
X07995Y0883631*
X0798876Y0883507*
X0798347Y0883154*
X0797993Y0882624*
X0797869Y0882*
X0797993Y0881376*
X0798347Y0880847*
X0798876Y0880493*
X07995Y0880369*
X0799684Y0880217*
Y07722*
X0799746Y0771888*
X0799923Y0771623*
X0800188Y0771446*
X08005Y0771384*
X0834*
X0834312Y0771446*
X0834577Y0771623*
X0834754Y0771888*
X0834816Y07722*
Y078374*
X0837778*
X0839275Y0782244*
Y0780496*
X0839093Y0780224*
X0838969Y07796*
X0839093Y0778976*
X0839447Y0778446*
X0839976Y0778093*
X08406Y0777969*
X0841224Y0778093*
X0841753Y0778446*
X0842107Y0778976*
X0842231Y07796*
X0842107Y0780224*
X0841926Y0780496*
Y0782793*
X0841825Y07833*
X0841537Y078373*
X0839732Y0785536*
Y078786*
X0834816*
Y0791146*
X083482*
Y0798454*
X0834816*
Y0801673*
X0837444*
Y0807683*
X0834816*
Y0809547*
X0837444*
Y0811329*
X0840059*
X0840159Y081121*
X0840043Y081057*
X0839595Y081027*
X0839087Y0809511*
X0838909Y0808615*
X0839087Y0807719*
X0839595Y080696*
X0840354Y0806452*
X084125Y0806274*
X0842146Y0806452*
X0842905Y080696*
X0843413Y0807719*
X0843591Y0808615*
X0843413Y0809511*
X0842905Y081027*
X084219Y0810748*
X0842179Y0810777*
X0842152Y0810984*
X0842161Y0811285*
X0842554Y0811547*
X0842907Y0812076*
X0843031Y08127*
X0842907Y0813324*
X0842554Y0813853*
X0842024Y0814207*
X08414Y0814331*
X0840776Y0814207*
X0840246Y0813853*
X0840132Y081383*
X084005Y0813776*
X0837444*
Y0815557*
X0834816*
Y0817421*
X0837444*
Y0818577*
X0839951*
X0840376Y0818293*
X0841Y0818169*
X0841624Y0818293*
X0842153Y0818647*
X0842507Y0819176*
X0842631Y08198*
X0842507Y0820424*
X0842153Y0820953*
X0841624Y0821307*
X0841Y0821431*
X0840376Y0821307*
X0839951Y0821023*
X0837444*
Y0823431*
X0834816*
Y0825295*
X0837444*
Y0826974*
X08388*
X0839307Y0827075*
X0839737Y0827363*
X0840703Y0828329*
X0841024Y0828393*
X0841553Y0828747*
X0841907Y0829276*
X0842031Y08299*
X0841907Y0830524*
X0841553Y0831054*
X0841024Y0831407*
X08404Y0831531*
X0839776Y0831407*
X0839246Y0831054*
X0838893Y0830524*
X0838829Y0830204*
X0838251Y0829626*
X0837444*
Y0831305*
X0834816*
Y0832662*
X0866468Y0864314*
X0866491Y0864348*
X0866522Y0864374*
X0866578Y086448*
X0866645Y0864579*
X0866653Y0864619*
X0866672Y0864655*
X0867Y0864869*
X0867624Y0864993*
X0868153Y0865347*
X0868507Y0865876*
X0868595Y0866319*
X0868631Y08665*
X0868845Y0866828*
X0868881Y0866847*
X0868921Y0866855*
X086902Y0866922*
X0869126Y0866978*
X0869152Y086701*
X0869186Y0867032*
X0870338Y0868184*
X0951091*
X0951242Y0867684*
X0951046Y0867554*
X0950693Y0867024*
X0950569Y08664*
X0950693Y0865776*
X0951046Y0865246*
X0951576Y0864893*
X09522Y0864769*
X0952824Y0864893*
X0953354Y0865246*
X0953707Y0865776*
X0953831Y08664*
X0953707Y0867024*
X0953354Y0867554*
X0953158Y0867684*
X095331Y0868184*
X09795*
X0979812Y0868246*
X0980077Y0868423*
X0990391Y0878738*
X0990568Y0879002*
X099063Y0879315*
X0991024Y0879776*
X0992993*
X1002777Y0869993*
Y0867949*
X1002493Y0867524*
X1002369Y08669*
X1002493Y0866276*
X1002847Y0865746*
X1003376Y0865393*
X1004Y0865269*
X1004624Y0865393*
X1005153Y0865746*
X1005507Y0866276*
X1005631Y08669*
X1005507Y0867524*
X1005223Y0867949*
Y08705*
X100513Y0870968*
X1004865Y0871365*
X0994365Y0881865*
X0994282Y0881921*
X0994207Y0882554*
X1005838Y0894184*
X1017162*
X1033184Y0878162*
Y0866684*
X0984052Y0817552*
X0983591Y0817798*
X0983631Y0818*
X0983507Y0818624*
X0983154Y0819153*
X0982624Y0819507*
X0982Y0819631*
X0981376Y0819507*
X0980847Y0819153*
X0980493Y0818624*
X0980369Y0818*
X0980493Y0817376*
X0980847Y0816846*
X0981376Y0816493*
X0982Y0816369*
X0982202Y0816409*
X0982448Y0815948*
X09815Y0815*
Y07205*
X10145Y06875*
X1267744*
X1267846Y0687347*
X1268376Y0686993*
X1269Y0686869*
X1269624Y0686993*
X1270154Y0687347*
X1270256Y06875*
X1289184*
Y0665338*
X1262782Y0638935*
X1262524Y0639107*
X12619Y0639231*
X1261276Y0639107*
X1260746Y0638754*
X1260393Y0638224*
X1260269Y06376*
X1260393Y0636976*
X1260565Y0636718*
X1257423Y0633577*
X1257246Y0633312*
X1257184Y0633*
Y06245*
X1257246Y0624188*
X1257423Y0623923*
X1263423Y0617923*
X1263688Y0617746*
X1264Y0617684*
X1277*
X1277312Y0617746*
X1277577Y0617923*
X1292038Y0632384*
X12925Y0632193*
Y0622*
X1232Y05615*
X09775*
X0862845Y0676156*
X0862854Y0676247*
X0863207Y0676776*
X0863331Y06774*
X0863207Y0678024*
X0862854Y0678553*
X0862324Y0678907*
X08617Y0679031*
X0861076Y0678907*
X0860546Y0678553*
X0860456Y0678545*
X0841565Y0697435*
X0841507Y0697724*
X0841154Y0698253*
X0840624Y0698607*
X0840335Y0698665*
X07346Y08044*
Y09345*
X0770233*
X0770444Y0934*
X0770193Y0933624*
X0770069Y0933*
X0770193Y0932376*
X0770546Y0931847*
X0771076Y0931493*
X07717Y0931369*
X0772324Y0931493*
X0772854Y0931847*
X0773207Y0932376*
X0773331Y0933*
X0773207Y0933624*
X0772956Y0934*
X0773167Y09345*
X077631*
X0776577Y0934*
X0776393Y0933724*
X0776269Y09331*
X0776393Y0932476*
X0776747Y0931946*
X0777276Y0931593*
X07779Y0931469*
X0778524Y0931593*
X0779053Y0931946*
X0779407Y0932476*
X0779531Y09331*
X0779407Y0933724*
X0779223Y0934*
X077949Y09345*
X1034*
Y0933816*
G37*
G36*
X12495Y09155D02*
Y0911529D01*
X1249356Y0911055*
X1249227Y090974*
X1249356Y0908426*
X12495Y0907951*
Y0872421*
X1249146Y0872069*
X123042Y0872159*
X1230351Y0872146*
X123028Y0872148*
X1230196Y0872116*
X1230108Y0872099*
X1230049Y0872059*
X1229982Y0872034*
X1229917Y0871972*
X1229842Y0871923*
X1229803Y0871864*
X1229751Y0871815*
X1229642Y0871661*
X1229124Y0872007*
X12285Y0872131*
X1227876Y0872007*
X1227686Y087188*
X1227176Y0871936*
X1227103Y0871985*
X1227041Y0872046*
X1226972Y0872073*
X1226912Y0872114*
X1226826Y0872131*
X1226745Y0872164*
X1226672Y0872163*
X12266Y0872178*
X1198004Y0872316*
X1198002Y0872315*
X1198Y0872316*
X1197845Y0872285*
X1197692Y0872255*
X119769Y0872254*
X1197688*
X1197558Y0872167*
X1197426Y087208*
X1197425Y0872078*
X1197423Y0872077*
X1186423Y0861077*
X1186246Y0860812*
X1186184Y08605*
Y08455*
X1186246Y0845188*
X1186423Y0844923*
X1231684Y0799662*
Y0740184*
X12295Y0738*
X1227966*
X1227756Y07385*
X1228007Y0738876*
X1228131Y07395*
X1228007Y0740124*
X1227654Y0740654*
X1227124Y0741007*
X12265Y0741131*
X1225876Y0741007*
X1225346Y0740654*
X1224993Y0740124*
X1224869Y07395*
X1224993Y0738876*
X1225244Y07385*
X1225033Y0738*
X1063*
X1034Y0767*
Y0771644*
X1034153Y0771746*
X1034507Y0772276*
X1034631Y07729*
X1034507Y0773524*
X1034153Y0774053*
X1034Y0774156*
Y0813742*
X1034031Y08139*
X1034Y0814058*
Y08785*
X10175Y0895*
X10055*
X0992723Y0882224*
X0983049*
X0982624Y0882507*
X0982Y0882631*
X0981376Y0882507*
X0980847Y0882154*
X0980493Y0881624*
X0980369Y0881*
X0980493Y0880376*
X0980847Y0879846*
X0981376Y0879493*
X0982Y0879369*
X0982624Y0879493*
X0983049Y0879776*
X0989623*
X0989815Y0879315*
X09795Y0869*
X087*
X0868609Y0867609*
X0868153Y0867653*
X0867624Y0868007*
X0867Y0868131*
X0866376Y0868007*
X0865847Y0867653*
X0865493Y0867124*
X0865369Y08665*
X0865493Y0865876*
X0865847Y0865347*
X0865891Y0864891*
X0834Y0833*
Y0831305*
X0827556*
Y0825295*
X0834*
Y0823431*
X0827556*
Y0817421*
X0834*
Y0815557*
X0827556*
Y0809547*
X0834*
Y07722*
X08005*
Y0880744*
X0800653Y0880847*
X0801007Y0881376*
X0801131Y0882*
X0801117Y0882073*
X0801175Y0882168*
X080155Y0882458*
X0802Y0882369*
X0802624Y0882493*
X0803154Y0882847*
X0803507Y0883376*
X0803631Y0884*
X0803507Y0884624*
X0803154Y0885153*
X0802624Y0885507*
X0802Y0885631*
X0801376Y0885507*
X0801Y0885256*
X08005Y0885466*
Y0902478*
X0800948Y0902699*
X080121Y0902499*
X0802073Y0902141*
X0803Y0902019*
X0803927Y0902141*
X080479Y0902499*
X0805532Y0903068*
X0806101Y090381*
X0806459Y0904673*
X0806581Y09056*
X0806459Y0906527*
X0806101Y090739*
X0805532Y0908132*
X080479Y0908701*
X0803927Y0909059*
X0803Y0909181*
X0802073Y0909059*
X080121Y0908701*
X0800948Y09085*
X08005Y0908722*
Y0912478*
X0800948Y09127*
X080121Y0912499*
X0802073Y0912141*
X0803Y0912019*
X0803927Y0912141*
X080479Y0912499*
X0805532Y0913068*
X0806101Y091381*
X0806459Y0914673*
X0806581Y09156*
X0806459Y0916527*
X0806101Y091739*
X0805532Y0918132*
X080479Y0918701*
X0803927Y0919059*
X0803Y0919181*
X0802073Y0919059*
X080121Y0918701*
X0800948Y0918501*
X08005Y0918722*
Y092205*
X080655*
Y092915*
X08005*
Y0933*
X1232*
X12495Y09155*
G37*
G36*
X1226596Y0871362D02*
X122694Y087086D01*
X1226869Y08705*
X1226993Y0869876*
X1227347Y0869347*
X1227876Y0868993*
X12285Y0868869*
X1229124Y0868993*
X1229653Y0869347*
X1230007Y0869876*
X1230131Y08705*
X1230063Y0870845*
X1230416Y0871343*
X13015Y0871*
X1322Y08505*
Y06635*
X1277Y06185*
X1264*
X1258Y06245*
Y0633*
X1261166Y0636166*
X1261276Y0636093*
X12619Y0635969*
X1262524Y0636093*
X1263054Y0636447*
X1263407Y0636976*
X1263531Y06376*
X1263407Y0638224*
X1263334Y0638334*
X129Y0665*
Y06995*
X1281Y07085*
X124*
X1239001Y0709499*
X1239146Y0709977*
X1239224Y0709993*
X1239754Y0710347*
X1240107Y0710876*
X1240231Y07115*
X1240107Y0712124*
X1239754Y0712653*
X1239224Y0713007*
X12386Y0713131*
X1237976Y0713007*
X1237446Y0712653*
X1237093Y0712124*
X1237077Y0712046*
X1236599Y0711901*
X12325Y0716*
Y08*
X1187Y08455*
Y08605*
X1198Y08715*
X1226596Y0871362*
G37*
%LNgrandmaster-2*%
%LPC*%
G36*
X074645Y092995D02*
X073935D01*
Y092285*
X074645*
Y092995*
G37*
G36*
X0777Y0917631D02*
X0776376Y0917507D01*
X0775846Y0917153*
X0775493Y0916624*
X0775369Y0916*
X0775493Y0915376*
X0775846Y0914847*
X0776376Y0914493*
X0777Y0914369*
X0777624Y0914493*
X0778154Y0914847*
X0778507Y0915376*
X0778631Y0916*
X0778507Y0916624*
X0778154Y0917153*
X0777624Y0917507*
X0777Y0917631*
G37*
G36*
X07429Y0919981D02*
X0741973Y0919859D01*
X074111Y0919501*
X0740368Y0918932*
X0739799Y091819*
X0739441Y0917327*
X0739319Y09164*
X0739441Y0915473*
X0739799Y091461*
X0740368Y0913868*
X074111Y0913299*
X0741973Y0912941*
X07429Y0912819*
X0743827Y0912941*
X074469Y0913299*
X0745432Y0913868*
X0746001Y091461*
X0746359Y0915473*
X0746481Y09164*
X0746359Y0917327*
X0746001Y091819*
X0745432Y0918932*
X074469Y0919501*
X0743827Y0919859*
X07429Y0919981*
G37*
G36*
X07576Y0914531D02*
X0756976Y0914407D01*
X0756447Y0914054*
X0756093Y0913524*
X0755969Y09129*
X0756093Y0912276*
X0756447Y0911747*
X0756976Y0911393*
X07576Y0911269*
X0758224Y0911393*
X0758753Y0911747*
X0759107Y0912276*
X0759231Y09129*
X0759107Y0913524*
X0758753Y0914054*
X0758224Y0914407*
X07576Y0914531*
G37*
G36*
X0774Y0913031D02*
X0773376Y0912907D01*
X0772847Y0912554*
X0772493Y0912024*
X0772369Y09114*
X0772493Y0910776*
X0772847Y0910246*
X0773376Y0909893*
X0774Y0909769*
X0774624Y0909893*
X0775153Y0910246*
X0775507Y0910776*
X0775631Y09114*
X0775507Y0912024*
X0775153Y0912554*
X0774624Y0912907*
X0774Y0913031*
G37*
G36*
X07682Y0909931D02*
X0767576Y0909807D01*
X0767046Y0909453*
X0766693Y0908924*
X0766569Y09083*
X0766693Y0907676*
X0767046Y0907146*
X0767576Y0906793*
X07682Y0906669*
X0768824Y0906793*
X0769353Y0907146*
X0769707Y0907676*
X0769831Y09083*
X0769707Y0908924*
X0769353Y0909453*
X0768824Y0909807*
X07682Y0909931*
G37*
G36*
X07429Y0909981D02*
X0741973Y0909859D01*
X074111Y0909501*
X0740368Y0908932*
X0739799Y090819*
X0739441Y0907327*
X0739319Y09064*
X0739441Y0905473*
X0739799Y090461*
X0740368Y0903868*
X074111Y0903299*
X0741973Y0902941*
X07429Y0902819*
X0743827Y0902941*
X074469Y0903299*
X0745432Y0903868*
X0746001Y090461*
X0746359Y0905473*
X0746481Y09064*
X0746359Y0907327*
X0746001Y090819*
X0745432Y0908932*
X074469Y0909501*
X0743827Y0909859*
X07429Y0909981*
G37*
G36*
X07894Y0903831D02*
X0788776Y0903707D01*
X0788246Y0903354*
X0787893Y0902824*
X0787769Y09022*
X0787893Y0901576*
X0788246Y0901046*
X0788776Y0900693*
X07894Y0900569*
X0790024Y0900693*
X0790554Y0901046*
X0790907Y0901576*
X0791031Y09022*
X0790907Y0902824*
X0790554Y0903354*
X0790024Y0903707*
X07894Y0903831*
G37*
G36*
X10076Y0891231D02*
X1006976Y0891107D01*
X1006446Y0890753*
X1006093Y0890224*
X1005969Y08896*
X1006093Y0888976*
X1006446Y0888447*
X1006976Y0888093*
X10076Y0887969*
X1008224Y0888093*
X1008753Y0888447*
X1009107Y0888976*
X1009231Y08896*
X1009107Y0890224*
X1008753Y0890753*
X1008224Y0891107*
X10076Y0891231*
G37*
G36*
X10185Y0890431D02*
X1017876Y0890307D01*
X1017346Y0889954*
X1016993Y0889424*
X1016869Y08888*
X1016993Y0888176*
X1017346Y0887646*
X1017876Y0887293*
X10185Y0887169*
X1019124Y0887293*
X1019654Y0887646*
X1020007Y0888176*
X1020131Y08888*
X1020007Y0889424*
X1019654Y0889954*
X1019124Y0890307*
X10185Y0890431*
G37*
G36*
X1003Y0880431D02*
X1002376Y0880307D01*
X1001847Y0879953*
X1001493Y0879424*
X1001369Y08788*
X1001493Y0878176*
X1001847Y0877647*
X1002376Y0877293*
X1003Y0877169*
X1003624Y0877293*
X1004154Y0877647*
X1004507Y0878176*
X1004631Y08788*
X1004507Y0879424*
X1004154Y0879953*
X1003624Y0880307*
X1003Y0880431*
G37*
G36*
X0784Y0872131D02*
X0783376Y0872007D01*
X0782846Y0871653*
X0782493Y0871124*
X0782369Y08705*
X0782493Y0869876*
X0782846Y0869347*
X0783376Y0868993*
X0784Y0868869*
X0784624Y0868993*
X0785153Y0869347*
X0785507Y0869876*
X0785631Y08705*
X0785507Y0871124*
X0785153Y0871653*
X0784624Y0872007*
X0784Y0872131*
G37*
G36*
X07745Y0868131D02*
X0773876Y0868007D01*
X0773347Y0867653*
X0772993Y0867124*
X0772869Y08665*
X0772993Y0865876*
X0773347Y0865347*
X0773876Y0864993*
X07745Y0864869*
X0775124Y0864993*
X0775654Y0865347*
X0776007Y0865876*
X0776131Y08665*
X0776007Y0867124*
X0775654Y0867653*
X0775124Y0868007*
X07745Y0868131*
G37*
G36*
X09415Y0865631D02*
X0940876Y0865507D01*
X0940347Y0865154*
X0939993Y0864624*
X0939869Y0864*
X0939993Y0863376*
X0940347Y0862846*
X0940876Y0862493*
X09415Y0862369*
X0942124Y0862493*
X0942653Y0862846*
X0943007Y0863376*
X0943131Y0864*
X0943007Y0864624*
X0942653Y0865154*
X0942124Y0865507*
X09415Y0865631*
G37*
G36*
X09265Y0862631D02*
X0925876Y0862507D01*
X0925346Y0862154*
X0924993Y0861624*
X0924869Y0861*
X0924873Y0860976*
X0924402Y0860781*
X0924154Y0861154*
X0923624Y0861507*
X0923Y0861631*
X0922376Y0861507*
X0921846Y0861154*
X0921493Y0860624*
X0921369Y086*
X0921493Y0859376*
X0921846Y0858846*
X0922376Y0858493*
X0923Y0858369*
X0923624Y0858493*
X0924154Y0858846*
X0924507Y0859376*
X0924631Y086*
X0924627Y0860024*
X0925098Y0860219*
X0925346Y0859846*
X0925876Y0859493*
X09265Y0859369*
X0927124Y0859493*
X0927654Y0859846*
X0928007Y0860376*
X0928131Y0861*
X0928007Y0861624*
X0927654Y0862154*
X0927124Y0862507*
X09265Y0862631*
G37*
G36*
X0879Y0863631D02*
X0878376Y0863507D01*
X0877847Y0863153*
X0877493Y0862624*
X0877369Y0862*
X0877493Y0861376*
X0877847Y0860847*
X0878376Y0860493*
X0879Y0860369*
X0879624Y0860493*
X0880153Y0860847*
X0880507Y0861376*
X0880631Y0862*
X0880507Y0862624*
X0880153Y0863153*
X0879624Y0863507*
X0879Y0863631*
G37*
G36*
X07875Y0862131D02*
X0786876Y0862007D01*
X0786346Y0861654*
X0785993Y0861124*
X0785869Y08605*
X0785993Y0859876*
X0786346Y0859346*
X0786876Y0858993*
X07875Y0858869*
X0788124Y0858993*
X0788654Y0859346*
X0789007Y0859876*
X0789131Y08605*
X0789007Y0861124*
X0788654Y0861654*
X0788124Y0862007*
X07875Y0862131*
G37*
G36*
X0754Y0864131D02*
X0753376Y0864007D01*
X0752846Y0863653*
X0752493Y0863124*
X0752369Y08625*
X0752493Y0861876*
X0752846Y0861347*
X0753376Y0860993*
X0754Y0860869*
X0754624Y0860993*
X0754649Y0861009*
X0755009Y0860649*
X0754993Y0860624*
X0754869Y086*
X0754993Y0859376*
X0755346Y0858846*
X0755876Y0858493*
X07565Y0858369*
X0757124Y0858493*
X0757654Y0858846*
X0758007Y0859376*
X0758131Y086*
X0758007Y0860624*
X0757654Y0861154*
X0757124Y0861507*
X07565Y0861631*
X0755876Y0861507*
X0755851Y0861491*
X0755491Y0861851*
X0755507Y0861876*
X0755631Y08625*
X0755507Y0863124*
X0755154Y0863653*
X0754624Y0864007*
X0754Y0864131*
G37*
G36*
X07431Y0857731D02*
X0742476Y0857607D01*
X0741947Y0857253*
X0741593Y0856724*
X0741469Y08561*
X0741593Y0855476*
X0741947Y0854947*
X0742476Y0854593*
X07431Y0854469*
X0743724Y0854593*
X0744253Y0854947*
X0744607Y0855476*
X0744731Y08561*
X0744607Y0856724*
X0744253Y0857253*
X0743724Y0857607*
X07431Y0857731*
G37*
G36*
X08715Y0854131D02*
X0870876Y0854007D01*
X0870347Y0853654*
X0869993Y0853124*
X0869869Y08525*
X0869993Y0851876*
X0870347Y0851346*
X0870876Y0850993*
X08715Y0850869*
X0872124Y0850993*
X0872653Y0851346*
X0873007Y0851876*
X0873131Y08525*
X0873007Y0853124*
X0872653Y0853654*
X0872124Y0854007*
X08715Y0854131*
G37*
G36*
X1012Y0853631D02*
X1011376Y0853507D01*
X1010847Y0853154*
X1010493Y0852624*
X1010369Y0852*
X1010493Y0851376*
X1010847Y0850846*
X1011376Y0850493*
X1012Y0850369*
X1012624Y0850493*
X1013153Y0850846*
X1013507Y0851376*
X1013631Y0852*
X1013507Y0852624*
X1013153Y0853154*
X1012624Y0853507*
X1012Y0853631*
G37*
G36*
X08665Y0852131D02*
X0865876Y0852007D01*
X0865347Y0851653*
X0864993Y0851124*
X0864869Y08505*
X0864993Y0849876*
X0865347Y0849347*
X0865876Y0848993*
X08665Y0848869*
X0867124Y0848993*
X0867653Y0849347*
X0868007Y0849876*
X0868131Y08505*
X0868007Y0851124*
X0867653Y0851653*
X0867124Y0852007*
X08665Y0852131*
G37*
G36*
X09613Y0850631D02*
X0960676Y0850507D01*
X0960147Y0850154*
X0959793Y0849624*
X0959669Y0849*
X0959793Y0848376*
X0960147Y0847847*
X0960676Y0847493*
X09613Y0847369*
X0961924Y0847493*
X0962453Y0847847*
X0962807Y0848376*
X0962931Y0849*
X0962807Y0849624*
X0962453Y0850154*
X0961924Y0850507*
X09613Y0850631*
G37*
G36*
X0857D02*
X0856376Y0850507D01*
X0855847Y0850154*
X0855493Y0849624*
X0855369Y0849*
X0855493Y0848376*
X0855847Y0847847*
X0856376Y0847493*
X0857Y0847369*
X0857624Y0847493*
X0858154Y0847847*
X0858507Y0848376*
X0858631Y0849*
X0858507Y0849624*
X0858154Y0850154*
X0857624Y0850507*
X0857Y0850631*
G37*
G36*
X0952Y0850131D02*
X0951376Y0850007D01*
X0950846Y0849654*
X0950493Y0849124*
X0950369Y08485*
X0950493Y0847876*
X0950846Y0847346*
X0951376Y0846993*
X0952Y0846869*
X0952624Y0846993*
X0953154Y0847346*
X0953507Y0847876*
X0953631Y08485*
X0953507Y0849124*
X0953154Y0849654*
X0952624Y0850007*
X0952Y0850131*
G37*
G36*
X09427Y0847731D02*
X0942076Y0847607D01*
X0941547Y0847254*
X0941193Y0846724*
X0941069Y08461*
X0941193Y0845476*
X0941547Y0844946*
X0942076Y0844593*
X09427Y0844469*
X0943324Y0844593*
X0943853Y0844946*
X0944039Y0845224*
X0944077Y0845237*
X0944617Y0845189*
X0944847Y0844847*
X0945376Y0844493*
X0946Y0844369*
X0946624Y0844493*
X0947153Y0844847*
X0947507Y0845376*
X0947631Y0846*
X0947507Y0846624*
X0947153Y0847153*
X0946624Y0847507*
X0946Y0847631*
X0945376Y0847507*
X0944847Y0847153*
X0944661Y0846876*
X0944623Y0846863*
X0944083Y084691*
X0943853Y0847254*
X0943324Y0847607*
X09427Y0847731*
G37*
G36*
X09349Y0846831D02*
X0934276Y0846707D01*
X0933747Y0846354*
X0933393Y0845824*
X0933269Y08452*
X0933393Y0844576*
X0933747Y0844046*
X0934276Y0843693*
X09349Y0843569*
X0935524Y0843693*
X0936053Y0844046*
X0936407Y0844576*
X0936435Y0844716*
X0936945*
X0936993Y0844476*
X0937346Y0843946*
X0937876Y0843593*
X09385Y0843469*
X0939124Y0843593*
X0939653Y0843946*
X0940007Y0844476*
X0940131Y08451*
X0940007Y0845724*
X0939653Y0846253*
X0939124Y0846607*
X09385Y0846731*
X0937876Y0846607*
X0937346Y0846253*
X0936993Y0845724*
X0936965Y0845584*
X0936455*
X0936407Y0845824*
X0936053Y0846354*
X0935524Y0846707*
X09349Y0846831*
G37*
G36*
X08961Y0843131D02*
X0895476Y0843007D01*
X0894946Y0842653*
X0894593Y0842124*
X0894469Y08415*
X0894593Y0840876*
X0894946Y0840347*
X0895476Y0839993*
X08961Y0839869*
X0896724Y0839993*
X0897254Y0840347*
X0897607Y0840876*
X0897731Y08415*
X0897607Y0842124*
X0897254Y0842653*
X0896724Y0843007*
X08961Y0843131*
G37*
G36*
X08625Y0842631D02*
X0861876Y0842507D01*
X0861347Y0842153*
X0860993Y0841624*
X0860869Y0841*
X0860993Y0840376*
X0861347Y0839847*
X0861876Y0839493*
X08625Y0839369*
X0863124Y0839493*
X0863653Y0839847*
X0864007Y0840376*
X0864131Y0841*
X0864007Y0841624*
X0863653Y0842153*
X0863124Y0842507*
X08625Y0842631*
G37*
G36*
X08887Y0839831D02*
X0888076Y0839707D01*
X0887547Y0839353*
X0887193Y0838824*
X0887069Y08382*
X0887193Y0837576*
X0887547Y0837047*
X0888076Y0836693*
X08887Y0836569*
X0889324Y0836693*
X0889853Y0837047*
X0890207Y0837576*
X0890331Y08382*
X0890207Y0838824*
X0889853Y0839353*
X0889324Y0839707*
X08887Y0839831*
G37*
G36*
X09293Y0836431D02*
X0928676Y0836307D01*
X0928146Y0835954*
X0927793Y0835424*
X0927669Y08348*
X0927793Y0834176*
X0928146Y0833646*
X0928676Y0833293*
X09293Y0833169*
X0929924Y0833293*
X0930453Y0833646*
X0930807Y0834176*
X0930931Y08348*
X0930807Y0835424*
X0930453Y0835954*
X0929924Y0836307*
X09293Y0836431*
G37*
G36*
X09735Y0836231D02*
X0972876Y0836107D01*
X0972346Y0835754*
X0971993Y0835224*
X0971869Y08346*
X0971993Y0833976*
X0972346Y0833447*
X0972876Y0833093*
X09735Y0832969*
X0974124Y0833093*
X0974654Y0833447*
X0975007Y0833976*
X0975131Y08346*
X0975007Y0835224*
X0974654Y0835754*
X0974124Y0836107*
X09735Y0836231*
G37*
G36*
X08717Y0834531D02*
X0871076Y0834407D01*
X0870547Y0834054*
X0870193Y0833524*
X0870069Y08329*
X0870193Y0832276*
X0870547Y0831746*
X0871076Y0831393*
X08717Y0831269*
X0872324Y0831393*
X0872853Y0831746*
X0873207Y0832276*
X0873331Y08329*
X0873207Y0833524*
X0872853Y0834054*
X0872324Y0834407*
X08717Y0834531*
G37*
G36*
X0953302Y0833929D02*
X0952678Y0833805D01*
X0952149Y0833451*
X0951795Y0832922*
X0951671Y0832298*
X0951795Y0831674*
X0952149Y0831144*
X0952678Y0830791*
X0953302Y0830666*
X0953926Y0830791*
X0954456Y0831144*
X0954809Y0831674*
X0954934Y0832298*
X0954809Y0832922*
X0954456Y0833451*
X0953926Y0833805*
X0953302Y0833929*
G37*
G36*
X09321Y0832131D02*
X0931476Y0832007D01*
X0930947Y0831653*
X0930593Y0831124*
X0930469Y08305*
X0930593Y0829876*
X0930947Y0829346*
X0931476Y0828993*
X09321Y0828869*
X0932724Y0828993*
X0933253Y0829346*
X0933607Y0829876*
X0933731Y08305*
X0933607Y0831124*
X0933253Y0831653*
X0932724Y0832007*
X09321Y0832131*
G37*
G36*
X09482Y0831731D02*
X0947576Y0831607D01*
X0947046Y0831254*
X0946693Y0830724*
X0946569Y08301*
X0946693Y0829476*
X0947046Y0828946*
X0947576Y0828593*
X09482Y0828469*
X0948824Y0828593*
X0949354Y0828946*
X0949707Y0829476*
X0949831Y08301*
X0949707Y0830724*
X0949354Y0831254*
X0948824Y0831607*
X09482Y0831731*
G37*
G36*
X09644Y0831331D02*
X0963776Y0831207D01*
X0963247Y0830853*
X0962893Y0830324*
X0962769Y08297*
X0962893Y0829076*
X0963247Y0828547*
X0963776Y0828193*
X09644Y0828069*
X0965024Y0828193*
X0965553Y0828547*
X0965907Y0829076*
X0966031Y08297*
X0965907Y0830324*
X0965553Y0830853*
X0965024Y0831207*
X09644Y0831331*
G37*
G36*
X09243D02*
X0923676Y0831207D01*
X0923147Y0830853*
X0922793Y0830324*
X0922669Y08297*
X0922793Y0829076*
X0923147Y0828547*
X0923676Y0828193*
X09243Y0828069*
X0924924Y0828193*
X0925453Y0828547*
X0925807Y0829076*
X0925931Y08297*
X0925807Y0830324*
X0925453Y0830853*
X0924924Y0831207*
X09243Y0831331*
G37*
G36*
X09365Y0829331D02*
X0935876Y0829207D01*
X0935347Y0828854*
X0934993Y0828324*
X0934869Y08277*
X0934993Y0827076*
X0935347Y0826546*
X0935876Y0826193*
X09365Y0826069*
X0937124Y0826193*
X0937654Y0826546*
X0938007Y0827076*
X0938131Y08277*
X0938007Y0828324*
X0937654Y0828854*
X0937124Y0829207*
X09365Y0829331*
G37*
G36*
X0854944Y0831305D02*
X0845056D01*
Y0825295*
X0854944*
Y0827077*
X08574*
X0857868Y082717*
X0858265Y0827435*
X0858473Y0827643*
X0858724Y0827693*
X0859254Y0828047*
X0859607Y0828576*
X0859731Y08292*
X0859607Y0829824*
X0859254Y0830354*
X0858724Y0830707*
X08581Y0830831*
X0857476Y0830707*
X0856946Y0830354*
X0856593Y0829824*
X0856533Y0829523*
X0854944*
Y0831305*
G37*
G36*
X09735Y0828131D02*
X0972876Y0828007D01*
X0972346Y0827654*
X0971993Y0827124*
X0971869Y08265*
X0971993Y0825876*
X0972346Y0825346*
X0972876Y0824993*
X09735Y0824869*
X0974124Y0824993*
X0974654Y0825346*
X0975007Y0825876*
X0975131Y08265*
X0975007Y0827124*
X0974654Y0827654*
X0974124Y0828007*
X09735Y0828131*
G37*
G36*
X0891732Y0822891D02*
X0891108Y0822767D01*
X0890684Y0822484*
X0890354Y0822442*
X0890024Y0822484*
X0889601Y0822767*
X0888976Y0822891*
X0888352Y0822767*
X0887823Y0822413*
X0887702Y0822233*
X0887101*
X088698Y0822413*
X0886451Y0822767*
X0885827Y0822891*
X0885203Y0822767*
X0884779Y0822484*
X0884449Y0822442*
X0884119Y0822484*
X0883695Y0822767*
X0883071Y0822891*
X0882447Y0822767*
X0881917Y0822413*
X0881564Y0821884*
X0881439Y082126*
X0881564Y0820636*
X0881917Y0820106*
X0882098Y0819986*
Y0819384*
X0881917Y0819264*
X0881564Y0818734*
X0881439Y081811*
X0881564Y0817486*
X0881917Y0816957*
X0882098Y0816836*
Y0816235*
X0881917Y0816114*
X0881564Y0815585*
X0881439Y0814961*
X0881564Y0814336*
X0881917Y0813807*
X0882098Y0813686*
Y0813085*
X0881917Y0812965*
X0881564Y0812435*
X0881439Y0811811*
X0881564Y0811187*
X0881917Y0810658*
X0882447Y0810304*
X0883071Y081018*
X0883695Y0810304*
X0884119Y0810587*
X0884449Y0810629*
X0884779Y0810587*
X0885203Y0810304*
X0885827Y081018*
X0886451Y0810304*
X088698Y0810658*
X0887101Y0810838*
X0887702*
X0887823Y0810658*
X0888352Y0810304*
X0888976Y081018*
X0889601Y0810304*
X0890024Y0810587*
X0890354Y0810629*
X0890684Y0810587*
X0891108Y0810304*
X0891732Y081018*
X0892357Y0810304*
X0892886Y0810658*
X0893239Y0811187*
X0893364Y0811811*
X0893239Y0812435*
X0892886Y0812965*
X0892705Y0813085*
Y0813686*
X0892886Y0813807*
X0893239Y0814336*
X0893364Y0814961*
X0893239Y0815585*
X0892886Y0816114*
X0892705Y0816235*
Y0816836*
X0892886Y0816957*
X0893239Y0817486*
X0893364Y081811*
X0893239Y0818734*
X0892886Y0819264*
X0892705Y0819384*
Y0819986*
X0892886Y0820106*
X0893239Y0820636*
X0893364Y082126*
X0893239Y0821884*
X0892886Y0822413*
X0892357Y0822767*
X0891732Y0822891*
G37*
G36*
X09221Y0825531D02*
X0921476Y0825407D01*
X0920947Y0825054*
X0920593Y0824524*
X0920469Y08239*
X0920593Y0823276*
X0920947Y0822746*
X0921476Y0822393*
X09221Y0822269*
X0922724Y0822393*
X0923254Y0822746*
X0923607Y0823276*
X0923731Y08239*
X0923607Y0824524*
X0923254Y0825054*
X0922724Y0825407*
X09221Y0825531*
G37*
G36*
X084125Y0826704D02*
X0840354Y0826526D01*
X0839595Y0826018*
X0839087Y0825259*
X0838909Y0824363*
X0839087Y0823467*
X0839595Y0822708*
X0840354Y08222*
X084125Y0822022*
X0842146Y08222*
X0842905Y0822708*
X0843413Y0823467*
X0843591Y0824363*
X0843413Y0825259*
X0842905Y0826018*
X0842146Y0826526*
X084125Y0826704*
G37*
G36*
X09188Y0823431D02*
X0918176Y0823307D01*
X0917647Y0822954*
X0917293Y0822424*
X0917169Y08218*
X0917293Y0821176*
X0917647Y0820646*
X0918176Y0820293*
X09188Y0820169*
X0919424Y0820293*
X0919954Y0820646*
X0920307Y0821176*
X0920431Y08218*
X0920307Y0822424*
X0919954Y0822954*
X0919424Y0823307*
X09188Y0823431*
G37*
G36*
X0903536Y0822996D02*
X0902911Y0822871D01*
X0902382Y0822518*
X0902029Y0821988*
X0901904Y0821364*
X0902029Y082074*
X0902382Y0820211*
X0902911Y0819857*
X0903536Y0819733*
X090416Y0819857*
X0904689Y0820211*
X0905043Y082074*
X0905167Y0821364*
X0905043Y0821988*
X0904689Y0822518*
X090416Y0822871*
X0903536Y0822996*
G37*
G36*
X09797Y0825531D02*
X0979076Y0825407D01*
X0978547Y0825054*
X0978193Y0824524*
X0978069Y08239*
X0978193Y0823276*
X0978547Y0822746*
X0978772Y0822596*
X0978666Y0822065*
X0978376Y0822007*
X0977847Y0821653*
X0977493Y0821124*
X0977369Y08205*
X0977493Y0819876*
X0977847Y0819347*
X0978376Y0818993*
X0979Y0818869*
X0979624Y0818993*
X0980153Y0819347*
X0980507Y0819876*
X0980631Y08205*
X0980507Y0821124*
X0980153Y0821653*
X0979928Y0821804*
X0980034Y0822335*
X0980324Y0822393*
X0980853Y0822746*
X0981207Y0823276*
X0981331Y08239*
X0981207Y0824524*
X0980853Y0825054*
X0980324Y0825407*
X09797Y0825531*
G37*
G36*
X0854944Y0823431D02*
X0845056D01*
Y0817421*
X0854944*
Y0819203*
X0857112*
X0857576Y0818893*
X08582Y0818769*
X0858824Y0818893*
X0859354Y0819246*
X0859707Y0819776*
X0859831Y08204*
X0859707Y0821024*
X0859354Y0821554*
X0858824Y0821907*
X08582Y0822031*
X0857576Y0821907*
X085719Y0821649*
X0854944*
Y0823431*
G37*
G36*
X08716Y0818031D02*
X0870976Y0817907D01*
X0870446Y0817554*
X0870093Y0817024*
X0869969Y08164*
X0870093Y0815776*
X0870446Y0815246*
X0870976Y0814893*
X08716Y0814769*
X0872224Y0814893*
X0872754Y0815246*
X0873107Y0815776*
X0873231Y08164*
X0873107Y0817024*
X0872754Y0817554*
X0872224Y0817907*
X08716Y0818031*
G37*
G36*
X09048Y0817531D02*
X0904176Y0817407D01*
X0903646Y0817054*
X0903293Y0816524*
X0903169Y08159*
X0903293Y0815276*
X0903646Y0814746*
X0904176Y0814393*
X09048Y0814269*
X0905424Y0814393*
X0905954Y0814746*
X0906307Y0815276*
X0906431Y08159*
X0906307Y0816524*
X0905954Y0817054*
X0905424Y0817407*
X09048Y0817531*
G37*
G36*
X0745Y0816731D02*
X0744376Y0816607D01*
X0743847Y0816253*
X0743493Y0815724*
X0743369Y08151*
X0743493Y0814476*
X0743847Y0813947*
X0744376Y0813593*
X0745Y0813469*
X0745624Y0813593*
X0746153Y0813947*
X0746507Y0814476*
X0746631Y08151*
X0746507Y0815724*
X0746153Y0816253*
X0745624Y0816607*
X0745Y0816731*
G37*
G36*
X09592Y0815831D02*
X0958576Y0815707D01*
X0958047Y0815353*
X0957693Y0814824*
X0957569Y08142*
X0957693Y0813576*
X0958047Y0813046*
X0958576Y0812693*
X09592Y0812569*
X0959824Y0812693*
X0960353Y0813046*
X0960707Y0813576*
X0960831Y08142*
X0960707Y0814824*
X0960353Y0815353*
X0959824Y0815707*
X09592Y0815831*
G37*
G36*
X09482Y0812331D02*
X0947576Y0812207D01*
X0947046Y0811854*
X0946693Y0811324*
X0946569Y08107*
X0946693Y0810076*
X0947046Y0809546*
X0947576Y0809193*
X09482Y0809069*
X0948824Y0809193*
X0949354Y0809546*
X0949707Y0810076*
X0949831Y08107*
X0949707Y0811324*
X0949354Y0811854*
X0948824Y0812207*
X09482Y0812331*
G37*
G36*
X0854944Y0815557D02*
X0845056D01*
Y0809547*
X0847653*
X0847958Y0809047*
X0847869Y08086*
X0847993Y0807976*
X0848347Y0807446*
X0848876Y0807093*
X08495Y0806969*
X0850124Y0807093*
X0850653Y0807446*
X0851007Y0807976*
X0851131Y08086*
X0851093Y0808792*
X085113Y0808848*
X0851223Y0809317*
Y0809547*
X0854944*
Y0815557*
G37*
G36*
X09708Y0809231D02*
X0970176Y0809107D01*
X0969646Y0808753*
X0969293Y0808224*
X0969169Y08076*
X0969293Y0806976*
X0969646Y0806446*
X0970176Y0806093*
X09708Y0805969*
X0971424Y0806093*
X0971953Y0806446*
X0972307Y0806976*
X0972431Y08076*
X0972307Y0808224*
X0971953Y0808753*
X0971424Y0809107*
X09708Y0809231*
G37*
G36*
X09359Y0807031D02*
X0935276Y0806907D01*
X0934746Y0806553*
X0934393Y0806024*
X0934269Y08054*
X0934393Y0804776*
X0934746Y0804247*
X0935276Y0803893*
X09359Y0803769*
X0936524Y0803893*
X0937053Y0804247*
X0937407Y0804776*
X0937531Y08054*
X0937407Y0806024*
X0937053Y0806553*
X0936524Y0806907*
X09359Y0807031*
G37*
G36*
X09335Y0801631D02*
X0932876Y0801507D01*
X0932347Y0801153*
X0931993Y0800624*
X0931869Y08*
X0931993Y0799376*
X0932347Y0798846*
X0932876Y0798493*
X09335Y0798369*
X0934124Y0798493*
X0934653Y0798846*
X0935007Y0799376*
X0935131Y08*
X0935007Y0800624*
X0934653Y0801153*
X0934124Y0801507*
X09335Y0801631*
G37*
G36*
X08975Y0806631D02*
X0896876Y0806507D01*
X0896346Y0806153*
X0895993Y0805624*
X0895869Y0805*
X0895993Y0804376*
X0896346Y0803846*
X0896876Y0803493*
X08975Y0803369*
X0897834Y0803435*
X090199Y0799279*
X0901826Y0798737*
X0901676Y0798707*
X0901147Y0798353*
X0900793Y0797824*
X0900669Y07972*
X0900793Y0796576*
X0901147Y0796046*
X0901676Y0795693*
X09023Y0795569*
X0902924Y0795693*
X0903454Y0796046*
X0903807Y0796576*
X0903878Y0796929*
X0903975Y0797208*
X0904421Y0797292*
X09045Y0797276*
X0905951*
X0906376Y0796993*
X0907Y0796869*
X0907624Y0796993*
X0908154Y0797346*
X0908507Y0797876*
X0908631Y07985*
X0908507Y0799124*
X0908154Y0799653*
X0907624Y0800007*
X0907Y0800131*
X0906376Y0800007*
X0905951Y0799723*
X0905007*
X0898865Y0805865*
X0898831Y0805888*
X0898654Y0806153*
X0898124Y0806507*
X08975Y0806631*
G37*
G36*
X08464Y0800031D02*
X0845776Y0799907D01*
X0845504Y0799725*
X0842443*
X0841936Y0799625*
X0841506Y0799337*
X0840649Y079848*
X0840607*
X0840479Y0798454*
X0835779*
Y0791146*
X0841907*
Y0796065*
X0842135Y0796217*
X0842992Y0797075*
X0845504*
X0845776Y0796893*
X08464Y0796769*
X0847024Y0796893*
X0847554Y0797247*
X0847907Y0797776*
X0848031Y07984*
X0847907Y0799024*
X0847554Y0799553*
X0847024Y0799907*
X08464Y0800031*
G37*
G36*
X09188Y0799031D02*
X0918176Y0798907D01*
X0917647Y0798554*
X0917293Y0798024*
X0917169Y07974*
X0917293Y0796776*
X0917647Y0796246*
X0918176Y0795893*
X09188Y0795769*
X0919424Y0795893*
X0919954Y0796246*
X0920307Y0796776*
X0920431Y07974*
X0920307Y0798024*
X0919954Y0798554*
X0919424Y0798907*
X09188Y0799031*
G37*
G36*
X0957Y0796331D02*
X0956376Y0796207D01*
X0955847Y0795854*
X0955493Y0795324*
X0955369Y07947*
X0955493Y0794076*
X0955847Y0793546*
X0956376Y0793193*
X0957Y0793069*
X0957624Y0793193*
X0958154Y0793546*
X0958507Y0794076*
X0958631Y07947*
X0958507Y0795324*
X0958154Y0795854*
X0957624Y0796207*
X0957Y0796331*
G37*
G36*
X08907Y0792331D02*
X0890076Y0792207D01*
X0889546Y0791854*
X0889267Y0791435*
X0888863Y0791368*
X0888696Y079139*
X0888653Y0791454*
X0888124Y0791807*
X08875Y0791931*
X0886876Y0791807*
X0886347Y0791454*
X0885993Y0790924*
X0885869Y07903*
X0885993Y0789676*
X0886347Y0789147*
X0886876Y0788793*
X08875Y0788669*
X0888124Y0788793*
X0888653Y0789147*
X0888933Y0789565*
X0889337Y0789632*
X0889504Y078961*
X0889546Y0789546*
X0890076Y0789193*
X08907Y0789069*
X0891324Y0789193*
X0891854Y0789546*
X0892207Y0790076*
X0892331Y07907*
X0892207Y0791324*
X0891854Y0791854*
X0891324Y0792207*
X08907Y0792331*
G37*
G36*
X087226Y0802846D02*
X086814D01*
Y0798568*
X0868874*
Y07936*
X0868975Y0793093*
X0869263Y0792663*
X0869829Y0792097*
X0869893Y0791776*
X0870247Y0791247*
X0870776Y0790893*
X08714Y0790769*
X0872024Y0790893*
X0872554Y0791247*
X0872907Y0791776*
X0873031Y07924*
X0872907Y0793024*
X0872554Y0793553*
X0872024Y0793907*
X0871704Y0793971*
X0871525Y0794149*
Y0798568*
X087226*
Y0802846*
G37*
G36*
X0909Y0793231D02*
X0908376Y0793107D01*
X0907847Y0792754*
X0907493Y0792224*
X0907369Y07916*
X0907493Y0790976*
X0907847Y0790447*
X0908376Y0790093*
X0909Y0789969*
X0909624Y0790093*
X0910153Y0790447*
X0910507Y0790976*
X0910631Y07916*
X0910507Y0792224*
X0910153Y0792754*
X0909624Y0793107*
X0909Y0793231*
G37*
G36*
X08807Y0792331D02*
X0880076Y0792207D01*
X0879547Y0791854*
X0879193Y0791324*
X0879069Y07907*
X0879193Y0790076*
X0879547Y0789546*
X0880076Y0789193*
X08807Y0789069*
X0881324Y0789193*
X0881853Y0789546*
X0882207Y0790076*
X0882331Y07907*
X0882207Y0791324*
X0881853Y0791854*
X0881324Y0792207*
X08807Y0792331*
G37*
G36*
X08753Y0792231D02*
X0874676Y0792107D01*
X0874146Y0791753*
X0873793Y0791224*
X0873669Y07906*
X0873793Y0789976*
X0874146Y0789446*
X0874676Y0789093*
X08753Y0788969*
X0875924Y0789093*
X0876453Y0789446*
X0876807Y0789976*
X0876931Y07906*
X0876807Y0791224*
X0876453Y0791753*
X0875924Y0792107*
X08753Y0792231*
G37*
G36*
X09009Y0791731D02*
X0900276Y0791607D01*
X0899747Y0791254*
X0899393Y0790724*
X0899269Y07901*
X0899393Y0789476*
X0899747Y0788946*
X0900276Y0788593*
X09009Y0788469*
X0901524Y0788593*
X0902054Y0788946*
X0902407Y0789476*
X0902531Y07901*
X0902407Y0790724*
X0902054Y0791254*
X0901524Y0791607*
X09009Y0791731*
G37*
G36*
X09592Y0791231D02*
X0958576Y0791107D01*
X0958047Y0790754*
X0957693Y0790224*
X0957569Y07896*
X0957693Y0788976*
X0958047Y0788447*
X0958576Y0788093*
X09592Y0787969*
X0959824Y0788093*
X0960353Y0788447*
X0960707Y0788976*
X0960831Y07896*
X0960707Y0790224*
X0960353Y0790754*
X0959824Y0791107*
X09592Y0791231*
G37*
G36*
X09361Y0790831D02*
X0935476Y0790707D01*
X0934947Y0790353*
X0934593Y0789824*
X0934469Y07892*
X0934593Y0788576*
X0934947Y0788047*
X0935476Y0787693*
X09361Y0787569*
X0936724Y0787693*
X0937253Y0788047*
X0937607Y0788576*
X0937731Y07892*
X0937607Y0789824*
X0937253Y0790353*
X0936724Y0790707*
X09361Y0790831*
G37*
G36*
X0865954Y080062D02*
X0858646D01*
Y0794493*
X0860975*
Y0789046*
X0860693Y0788624*
X0860569Y0788*
X0860693Y0787376*
X0861047Y0786846*
X0861576Y0786493*
X08622Y0786369*
X0862824Y0786493*
X0863354Y0786846*
X0863707Y0787376*
X0863831Y0788*
X0863707Y0788624*
X0863626Y0788747*
Y0794493*
X0865954*
Y080062*
G37*
G36*
X08485Y0771631D02*
X0847876Y0771507D01*
X0847346Y0771153*
X0846993Y0770624*
X0846869Y077*
X0846993Y0769376*
X0847346Y0768847*
X0847848Y0768511*
X0847876Y0768298*
Y0768202*
X0847848Y0767989*
X0847346Y0767654*
X0846993Y0767124*
X0846869Y07665*
X0846993Y0765876*
X0847346Y0765346*
X0847876Y0764993*
X08485Y0764869*
X0849124Y0764993*
X0849654Y0765346*
X0850007Y0765876*
X0850131Y07665*
X0850007Y0767124*
X0849654Y0767654*
X0849152Y0767989*
X0849124Y0768202*
Y0768298*
X0849152Y0768511*
X0849654Y0768847*
X0850007Y0769376*
X0850131Y077*
X0850007Y0770624*
X0849654Y0771153*
X0849124Y0771507*
X08485Y0771631*
G37*
G36*
X08949Y0764131D02*
X0894276Y0764007D01*
X0893746Y0763654*
X0893393Y0763124*
X0893269Y07625*
X0893393Y0761876*
X0893746Y0761346*
X0894276Y0760993*
X08949Y0760869*
X0895524Y0760993*
X0896054Y0761346*
X0896407Y0761876*
X0896531Y07625*
X0896407Y0763124*
X0896054Y0763654*
X0895524Y0764007*
X08949Y0764131*
G37*
G36*
X0841935D02*
X0841311Y0764007D01*
X0840781Y0763654*
X0840428Y0763124*
X0840304Y07625*
X0840428Y0761876*
X0840781Y0761346*
X0841311Y0760993*
X0841935Y0760869*
X0842559Y0760993*
X0843089Y0761346*
X0843442Y0761876*
X0843566Y07625*
X0843442Y0763124*
X0843089Y0763654*
X0842559Y0764007*
X0841935Y0764131*
G37*
G36*
X082425Y0763381D02*
X0823626Y0763257D01*
X0823096Y0762903*
X0822743Y0762374*
X0822619Y076175*
X0822743Y0761126*
X0822991Y0760755*
X0822661Y0760348*
X082219Y0760441*
X0821566Y0760317*
X0821037Y0759964*
X0820683Y0759434*
X0820559Y075881*
X0820683Y0758186*
X0821037Y0757656*
X0821566Y0757303*
X082219Y0757179*
X0822814Y0757303*
X0823343Y0757656*
X0823697Y0758186*
X0823821Y075881*
X0823697Y0759434*
X082345Y0759805*
X0823779Y0760212*
X082425Y0760119*
X0824874Y0760243*
X0825403Y0760597*
X0825757Y0761126*
X0825881Y076175*
X0825757Y0762374*
X0825403Y0762903*
X0824874Y0763257*
X082425Y0763381*
G37*
G36*
X08812Y0762131D02*
X0880576Y0762007D01*
X0880046Y0761654*
X0879693Y0761124*
X0879569Y07605*
X0879693Y0759876*
X0880046Y0759346*
X0880576Y0758993*
X08812Y0758869*
X0881824Y0758993*
X0882353Y0759346*
X0882707Y0759876*
X0882831Y07605*
X0882707Y0761124*
X0882353Y0761654*
X0881824Y0762007*
X08812Y0762131*
G37*
G36*
X09614Y0760731D02*
X0960776Y0760607D01*
X0960246Y0760253*
X0959893Y0759724*
X0959769Y07591*
X0959893Y0758476*
X0960246Y0757946*
X0960776Y0757593*
X09614Y0757469*
X0962024Y0757593*
X0962554Y0757946*
X0962907Y0758476*
X0963031Y07591*
X0962907Y0759724*
X0962554Y0760253*
X0962024Y0760607*
X09614Y0760731*
G37*
G36*
X0957Y0760631D02*
X0956376Y0760507D01*
X0955847Y0760153*
X0955493Y0759624*
X0955369Y0759*
X0955493Y0758376*
X0955847Y0757846*
X0956376Y0757493*
X0957Y0757369*
X0957624Y0757493*
X0958154Y0757846*
X0958507Y0758376*
X0958631Y0759*
X0958507Y0759624*
X0958154Y0760153*
X0957624Y0760507*
X0957Y0760631*
G37*
G36*
X08314D02*
X0830776Y0760507D01*
X0830247Y0760153*
X0829893Y0759624*
X0829769Y0759*
X0829893Y0758376*
X0830247Y0757846*
X0830776Y0757493*
X08314Y0757369*
X0832024Y0757493*
X0832553Y0757846*
X0832907Y0758376*
X0833031Y0759*
X0832907Y0759624*
X0832553Y0760153*
X0832024Y0760507*
X08314Y0760631*
G37*
G36*
X084Y0759931D02*
X0839376Y0759807D01*
X0838846Y0759453*
X0838493Y0758924*
X0838369Y07583*
X0838493Y0757676*
X0838846Y0757147*
X0839376Y0756793*
X084Y0756669*
X0840624Y0756793*
X0841154Y0757147*
X0841507Y0757676*
X0841631Y07583*
X0841507Y0758924*
X0841154Y0759453*
X0840624Y0759807*
X084Y0759931*
G37*
G36*
X08577Y0758931D02*
X0857076Y0758807D01*
X0856546Y0758454*
X0856193Y0757924*
X0856069Y07573*
X0856193Y0756676*
X0856546Y0756146*
X0857076Y0755793*
X08577Y0755669*
X0858324Y0755793*
X0858854Y0756146*
X0859207Y0756676*
X0859331Y07573*
X0859207Y0757924*
X0858854Y0758454*
X0858324Y0758807*
X08577Y0758931*
G37*
G36*
X08774Y0758831D02*
X0876776Y0758707D01*
X0876246Y0758354*
X0875893Y0757824*
X0875769Y07572*
X0875893Y0756576*
X0876246Y0756046*
X0876776Y0755693*
X08774Y0755569*
X0878024Y0755693*
X0878553Y0756046*
X0878907Y0756576*
X0879031Y07572*
X0878907Y0757824*
X0878553Y0758354*
X0878024Y0758707*
X08774Y0758831*
G37*
G36*
X08676D02*
X0866976Y0758707D01*
X0866446Y0758354*
X0866093Y0757824*
X0865969Y07572*
X0866093Y0756576*
X0866446Y0756046*
X0866976Y0755693*
X08676Y0755569*
X0868224Y0755693*
X0868754Y0756046*
X0869107Y0756576*
X0869231Y07572*
X0869107Y0757824*
X0868754Y0758354*
X0868224Y0758707*
X08676Y0758831*
G37*
G36*
X08872Y0758631D02*
X0886576Y0758507D01*
X0886047Y0758153*
X0885693Y0757624*
X0885569Y0757*
X0885693Y0756376*
X0886047Y0755847*
X0886576Y0755493*
X08872Y0755369*
X0887824Y0755493*
X0888354Y0755847*
X0888707Y0756376*
X0888831Y0757*
X0888707Y0757624*
X0888354Y0758153*
X0887824Y0758507*
X08872Y0758631*
G37*
G36*
X08615Y0748131D02*
X0860876Y0748007D01*
X0860347Y0747653*
X0859993Y0747124*
X0859869Y07465*
X0859993Y0745876*
X0860009Y0745851*
X0859649Y0745491*
X0859624Y0745507*
X0859Y0745631*
X0858376Y0745507*
X0857847Y0745154*
X0857493Y0744624*
X0857369Y0744*
X0857462Y0743531*
X0857414Y0743446*
X0857154Y0743186*
X0857069Y0743138*
X08566Y0743231*
X0855976Y0743107*
X0855447Y0742754*
X0855093Y0742224*
X0854969Y07416*
X0855093Y0740976*
X0855447Y0740447*
X0855976Y0740093*
X08566Y0739969*
X0857224Y0740093*
X0857753Y0740447*
X0858107Y0740976*
X0858231Y07416*
X0858138Y0742069*
X0858186Y0742154*
X0858446Y0742414*
X0858531Y0742462*
X0859Y0742369*
X0859624Y0742493*
X0860153Y0742846*
X0860507Y0743376*
X0860631Y0744*
X0860507Y0744624*
X0860491Y0744649*
X0860851Y0745009*
X0860876Y0744993*
X08615Y0744869*
X0862124Y0744993*
X0862654Y0745346*
X0863007Y0745876*
X0863131Y07465*
X0863007Y0747124*
X0862654Y0747653*
X0862124Y0748007*
X08615Y0748131*
G37*
G36*
X0826219Y0748412D02*
X0825595Y0748288D01*
X0825066Y0747934*
X0824712Y0747405*
X0824588Y0746781*
X0824712Y0746157*
X0825066Y0745627*
X0825595Y0745274*
X0826219Y074515*
X0826843Y0745274*
X0827372Y0745627*
X0827726Y0746157*
X082785Y0746781*
X0827726Y0747405*
X0827372Y0747934*
X0826843Y0748288*
X0826219Y0748412*
G37*
G36*
X08516Y0748331D02*
X0850976Y0748207D01*
X0850447Y0747854*
X0850093Y0747324*
X0849969Y07467*
X0850093Y0746076*
X0850447Y0745546*
X0850976Y0745193*
X08516Y0745069*
X0852224Y0745193*
X0852754Y0745546*
X0853107Y0746076*
X0853231Y07467*
X0853107Y0747324*
X0852754Y0747854*
X0852224Y0748207*
X08516Y0748331*
G37*
G36*
X08939Y0747631D02*
X0893276Y0747507D01*
X0892747Y0747154*
X0892393Y0746624*
X0892269Y0746*
X0892393Y0745376*
X0892747Y0744846*
X0893276Y0744493*
X08939Y0744369*
X0894524Y0744493*
X0895053Y0744846*
X0895407Y0745376*
X0895531Y0746*
X0895407Y0746624*
X0895053Y0747154*
X0894524Y0747507*
X08939Y0747631*
G37*
G36*
X08466D02*
X0845976Y0747507D01*
X0845446Y0747154*
X0845093Y0746624*
X0844969Y0746*
X0845093Y0745376*
X0845446Y0744846*
X0845976Y0744493*
X08466Y0744369*
X0847224Y0744493*
X0847754Y0744846*
X0848107Y0745376*
X0848231Y0746*
X0848107Y0746624*
X0847754Y0747154*
X0847224Y0747507*
X08466Y0747631*
G37*
G36*
X0898069Y0746167D02*
X0897334Y0746021D01*
X0896711Y0745605*
X0896295Y0744982*
X0896149Y0744247*
X0896295Y0743512*
X0896711Y0742889*
X0897334Y0742473*
X0898069Y0742327*
X0898804Y0742473*
X0899427Y0742889*
X0899843Y0743512*
X0899989Y0744247*
X0899843Y0744982*
X0899427Y0745605*
X0898804Y0746021*
X0898069Y0746167*
G37*
G36*
X0819329D02*
X0818594Y0746021D01*
X0817971Y0745605*
X0817555Y0744982*
X0817409Y0744247*
X0817555Y0743512*
X0817971Y0742889*
X0818594Y0742473*
X0819329Y0742327*
X0820064Y0742473*
X0820687Y0742889*
X0821103Y0743512*
X0821249Y0744247*
X0821103Y0744982*
X0820687Y0745605*
X0820064Y0746021*
X0819329Y0746167*
G37*
G36*
X096081Y0755761D02*
X0959496Y0755631D01*
X0958232Y0755248*
X0957067Y0754625*
X0956046Y0753787*
X0955208Y0752766*
X0954585Y0751602*
X0954202Y0750338*
X0954072Y0749023*
X0954202Y0747709*
X0954585Y0746445*
X0955208Y074528*
X0956046Y0744259*
X0957067Y0743421*
X0958232Y0742798*
X0959496Y0742415*
X096081Y0742285*
X0962125Y0742415*
X0963389Y0742798*
X0964553Y0743421*
X0965574Y0744259*
X0966412Y074528*
X0967035Y0746445*
X0967418Y0747709*
X0967548Y0749023*
X0967418Y0750338*
X0967035Y0751602*
X0966412Y0752766*
X0965574Y0753787*
X0964553Y0754625*
X0963389Y0755248*
X0962125Y0755631*
X096081Y0755761*
G37*
G36*
X08774Y0744931D02*
X0876776Y0744807D01*
X0876246Y0744453*
X0875893Y0743924*
X0875769Y07433*
X0875893Y0742676*
X0876246Y0742146*
X0876776Y0741793*
X08774Y0741669*
X0878024Y0741793*
X0878553Y0742146*
X0878907Y0742676*
X0879031Y07433*
X0878907Y0743924*
X0878553Y0744453*
X0878024Y0744807*
X08774Y0744931*
G37*
G36*
X08885Y0745131D02*
X0887876Y0745007D01*
X0887346Y0744654*
X0886993Y0744124*
X0886869Y07435*
X0886993Y0742876*
X0887346Y0742346*
X0887876Y0741993*
X08885Y0741869*
X0889124Y0741993*
X0889302Y0742111*
X0889946Y0742046*
X0890476Y0741693*
X08911Y0741569*
X0891724Y0741693*
X0892253Y0742046*
X0892607Y0742576*
X0892731Y07432*
X0892607Y0743824*
X0892253Y0744353*
X0891724Y0744707*
X08911Y0744831*
X0890476Y0744707*
X0889946Y0744353*
X0889854*
X0889653Y0744654*
X0889124Y0745007*
X08885Y0745131*
G37*
G36*
X08479Y0743331D02*
X0847276Y0743207D01*
X0846747Y0742853*
X0846393Y0742324*
X0846269Y07417*
X0846393Y0741076*
X0846747Y0740547*
X0847276Y0740193*
X08479Y0740069*
X0848524Y0740193*
X0849053Y0740547*
X0849407Y0741076*
X0849531Y07417*
X0849407Y0742324*
X0849053Y0742853*
X0848524Y0743207*
X08479Y0743331*
G37*
G36*
X08395Y0743231D02*
X0838876Y0743107D01*
X0838346Y0742754*
X0837993Y0742224*
X0837869Y07416*
X0837993Y0740976*
X0838346Y0740447*
X0838876Y0740093*
X08395Y0739969*
X0840124Y0740093*
X0840654Y0740447*
X0841007Y0740976*
X0841131Y07416*
X0841007Y0742224*
X0840654Y0742754*
X0840124Y0743107*
X08395Y0743231*
G37*
G36*
X09489Y0736131D02*
X0948276Y0736007D01*
X0947746Y0735653*
X0947393Y0735124*
X0947269Y07345*
X0947393Y0733876*
X0947746Y0733347*
X0948276Y0732993*
X09489Y0732869*
X0949524Y0732993*
X0950054Y0733347*
X0950407Y0733876*
X0950531Y07345*
X0950407Y0735124*
X0950054Y0735653*
X0949524Y0736007*
X09489Y0736131*
G37*
G36*
X08466Y0731131D02*
X0845976Y0731007D01*
X0845446Y0730653*
X0845093Y0730124*
X0844585Y0730135*
X08441Y0730231*
X0843476Y0730107*
X0842947Y0729753*
X0842593Y0729224*
X0842469Y07286*
X0842593Y0727976*
X0842947Y0727447*
X0843476Y0727093*
X08441Y0726969*
X0844724Y0727093*
X0845253Y0727447*
X0845451Y0727742*
X0845926Y0727969*
X0846115Y0727965*
X08466Y0727869*
X0847224Y0727993*
X0847754Y0728346*
X0848107Y0728876*
X0848231Y07295*
X0848107Y0730124*
X0847754Y0730653*
X0847224Y0731007*
X08466Y0731131*
G37*
G36*
X08794Y0732731D02*
X0878776Y0732607D01*
X0878246Y0732254*
X0877893Y0731724*
X0877769Y07311*
X0877893Y0730476*
X0878246Y0729947*
X0878776Y0729593*
X08794Y0729469*
X0880024Y0729593*
X0880554Y0729947*
X0880907Y0730476*
X0881031Y07311*
X0880907Y0731724*
X0880554Y0732254*
X0880024Y0732607*
X08794Y0732731*
G37*
G36*
X08676Y0733131D02*
X0866976Y0733007D01*
X0866446Y0732654*
X0866093Y0732124*
X0865982Y0731565*
X0865888Y0731397*
X0865703Y0731212*
X0865535Y0731118*
X0864976Y0731007*
X0864447Y0730653*
X0864093Y0730124*
X0863969Y07295*
X086385Y0729382*
X08636Y0729431*
X0862976Y0729307*
X0862446Y0728954*
X0862093Y0728424*
X0861969Y07278*
X0862093Y0727176*
X0862446Y0726647*
X0862976Y0726293*
X08636Y0726169*
X0864224Y0726293*
X0864754Y0726647*
X0865107Y0727176*
X0865231Y07278*
X086535Y0727918*
X08656Y0727869*
X0866224Y0727993*
X0866753Y0728346*
X0867107Y0728876*
X0867195Y0729315*
X0867669Y07293*
X0867793Y0728676*
X0868147Y0728147*
X0868676Y0727793*
X08693Y0727669*
X0869924Y0727793*
X0870453Y0728147*
X0870667Y0728466*
X0871076Y0728193*
X08717Y0728069*
X0872324Y0728193*
X0872853Y0728546*
X0873207Y0729076*
X0873331Y07297*
X0873207Y0730324*
X0872853Y0730854*
X0872324Y0731207*
X08717Y0731331*
X0871076Y0731207*
X0870547Y0730854*
X0870333Y0730534*
X0869924Y0730807*
X0869616Y0730869*
X0869208Y0731384*
X0869231Y07315*
X0869107Y0732124*
X0868754Y0732654*
X0868224Y0733007*
X08676Y0733131*
G37*
G36*
X08862Y0731731D02*
X0885576Y0731607D01*
X0885046Y0731253*
X0884693Y0730724*
X0884569Y07301*
X0884693Y0729476*
X0885046Y0728946*
X0885576Y0728593*
X08862Y0728469*
X0886824Y0728593*
X0887354Y0728946*
X0887707Y0729476*
X0887831Y07301*
X0887707Y0730724*
X0887354Y0731253*
X0886824Y0731607*
X08862Y0731731*
G37*
G36*
X08976Y0730731D02*
X0896976Y0730607D01*
X0896447Y0730254*
X0896093Y0729724*
X0895969Y07291*
X0896093Y0728476*
X0896447Y0727947*
X0896976Y0727593*
X08976Y0727469*
X0898224Y0727593*
X0898754Y0727947*
X0899107Y0728476*
X0899231Y07291*
X0899107Y0729724*
X0898754Y0730254*
X0898224Y0730607*
X08976Y0730731*
G37*
G36*
X08933Y0730631D02*
X0892676Y0730507D01*
X0892146Y0730154*
X0891793Y0729624*
X0891669Y0729*
X0891793Y0728376*
X0892146Y0727846*
X0892676Y0727493*
X08933Y0727369*
X0893924Y0727493*
X0894454Y0727846*
X0894807Y0728376*
X0894931Y0729*
X0894807Y0729624*
X0894454Y0730154*
X0893924Y0730507*
X08933Y0730631*
G37*
G36*
X084Y0733431D02*
X0839376Y0733307D01*
X0838846Y0732954*
X0838493Y0732424*
X0838369Y07318*
X0838493Y0731176*
X0838846Y0730647*
X083899Y0730551*
Y0729949*
X0838846Y0729853*
X0838493Y0729324*
X0838369Y07287*
X0838493Y0728076*
X0838846Y0727547*
X0839376Y0727193*
X084Y0727069*
X0840624Y0727193*
X0841154Y0727547*
X0841507Y0728076*
X0841631Y07287*
X0841507Y0729324*
X0841154Y0729853*
X084101Y0729949*
Y0730551*
X0841154Y0730647*
X0841507Y0731176*
X0841631Y07318*
X0841507Y0732424*
X0841154Y0732954*
X0840624Y0733307*
X084Y0733431*
G37*
G36*
X08572Y0732831D02*
X0856576Y0732707D01*
X0856046Y0732353*
X0855693Y0731824*
X0855569Y07312*
X0855693Y0730576*
X0855888Y0730283*
X0855847Y0729654*
X0855493Y0729124*
X0855369Y07285*
X0855493Y0727876*
X0855847Y0727347*
X0856376Y0726993*
X0857Y0726869*
X0857624Y0726993*
X0858154Y0727347*
X0858507Y0727876*
X0858631Y07285*
X0858507Y0729124*
X0858311Y0729417*
X0858354Y0730047*
X0858707Y0730576*
X0858831Y07312*
X0858707Y0731824*
X0858354Y0732353*
X0857824Y0732707*
X08572Y0732831*
G37*
G36*
X08244Y0729931D02*
X0823776Y0729807D01*
X0823246Y0729454*
X0822893Y0728924*
X0822769Y07283*
X0822893Y0727676*
X0823246Y0727146*
X0823776Y0726793*
X08244Y0726669*
X0825024Y0726793*
X0825554Y0727146*
X0825907Y0727676*
X0826031Y07283*
X0825907Y0728924*
X0825554Y0729454*
X0825024Y0729807*
X08244Y0729931*
G37*
G36*
X09333Y0728331D02*
X0932676Y0728207D01*
X0932146Y0727853*
X0931793Y0727324*
X0931669Y07267*
X0931793Y0726076*
X0932146Y0725547*
X0932676Y0725193*
X09333Y0725069*
X0933924Y0725193*
X0934453Y0725547*
X0934807Y0726076*
X0934931Y07267*
X0934807Y0727324*
X0934453Y0727853*
X0933924Y0728207*
X09333Y0728331*
G37*
G36*
X08832D02*
X0882576Y0728207D01*
X0882047Y0727853*
X0881693Y0727324*
X0881569Y07267*
X0881693Y0726076*
X0882047Y0725547*
X0882576Y0725193*
X08832Y0725069*
X0883824Y0725193*
X0884354Y0725547*
X0884707Y0726076*
X0884831Y07267*
X0884707Y0727324*
X0884354Y0727853*
X0883824Y0728207*
X08832Y0728331*
G37*
G36*
X0849Y0725631D02*
X0848376Y0725507D01*
X0847847Y0725153*
X0847493Y0724624*
X0847369Y0724*
X0847493Y0723376*
X0847847Y0722847*
X0848376Y0722493*
X0849Y0722369*
X0849624Y0722493*
X0850154Y0722847*
X0850507Y0723376*
X0850631Y0724*
X0850507Y0724624*
X0850154Y0725153*
X0849624Y0725507*
X0849Y0725631*
G37*
G36*
X08321Y0723531D02*
X0831476Y0723407D01*
X0830947Y0723054*
X0830593Y0722524*
X0830469Y07219*
X0830593Y0721276*
X0830947Y0720747*
X0831476Y0720393*
X08321Y0720269*
X0832724Y0720393*
X0833253Y0720747*
X0833607Y0721276*
X0833731Y07219*
X0833607Y0722524*
X0833253Y0723054*
X0832724Y0723407*
X08321Y0723531*
G37*
G36*
X095619Y0712033D02*
X0955455Y0711887D01*
X0954832Y0711471*
X0954416Y0710848*
X095427Y0710113*
X0954416Y0709378*
X0954832Y0708755*
X0955455Y0708339*
X095619Y0708193*
X0956925Y0708339*
X0957548Y0708755*
X0957964Y0709378*
X095811Y0710113*
X0957964Y0710848*
X0957548Y0711471*
X0956925Y0711887*
X095619Y0712033*
G37*
G36*
X0971Y0701631D02*
X0970376Y0701507D01*
X0969847Y0701154*
X0969493Y0700624*
X0969369Y07*
X0969493Y0699376*
X0969847Y0698846*
X0970376Y0698493*
X0971Y0698369*
X0971624Y0698493*
X0972153Y0698846*
X0972507Y0699376*
X0972631Y07*
X0972507Y0700624*
X0972153Y0701154*
X0971624Y0701507*
X0971Y0701631*
G37*
G36*
X09545Y0701131D02*
X0953876Y0701007D01*
X0953347Y0700654*
X0952993Y0700124*
X0952869Y06995*
X0952993Y0698876*
X0953347Y0698347*
X0953876Y0697993*
X09545Y0697869*
X0955124Y0697993*
X0955653Y0698347*
X0956007Y0698876*
X0956131Y06995*
X0956007Y0700124*
X0955653Y0700654*
X0955124Y0701007*
X09545Y0701131*
G37*
G36*
X09289Y0699131D02*
X0928276Y0699007D01*
X0927746Y0698654*
X0927393Y0698124*
X0927269Y06975*
X0927393Y0696876*
X0927746Y0696347*
X0928276Y0695993*
X09289Y0695869*
X0929524Y0695993*
X0930054Y0696347*
X0930407Y0696876*
X0930531Y06975*
X0930407Y0698124*
X0930054Y0698654*
X0929524Y0699007*
X09289Y0699131*
G37*
G36*
X09545Y0696131D02*
X0953876Y0696007D01*
X0953347Y0695653*
X0952993Y0695124*
X0952869Y06945*
X0952993Y0693876*
X0953347Y0693347*
X0953876Y0692993*
X09545Y0692869*
X0955124Y0692993*
X0955653Y0693347*
X0956007Y0693876*
X0956131Y06945*
X0956007Y0695124*
X0955653Y0695653*
X0955124Y0696007*
X09545Y0696131*
G37*
G36*
X0971Y0694131D02*
X0970376Y0694007D01*
X0969847Y0693653*
X0969493Y0693124*
X0969369Y06925*
X0969493Y0691876*
X0969847Y0691347*
X0970376Y0690993*
X0971Y0690869*
X0971624Y0690993*
X0972153Y0691347*
X0972507Y0691876*
X0972631Y06925*
X0972507Y0693124*
X0972153Y0693653*
X0971624Y0694007*
X0971Y0694131*
G37*
G36*
X09545Y0691131D02*
X0953876Y0691007D01*
X0953347Y0690654*
X0952993Y0690124*
X0952869Y06895*
X0952993Y0688876*
X0953347Y0688346*
X0953876Y0687993*
X09545Y0687869*
X0955124Y0687993*
X0955653Y0688346*
X0956007Y0688876*
X0956131Y06895*
X0956007Y0690124*
X0955653Y0690654*
X0955124Y0691007*
X09545Y0691131*
G37*
G36*
X09383Y0689131D02*
X0937676Y0689007D01*
X0937146Y0688654*
X0936793Y0688124*
X0936669Y06875*
X0936793Y0686876*
X0937146Y0686346*
X0937676Y0685993*
X09383Y0685869*
X0938924Y0685993*
X0939454Y0686346*
X0939807Y0686876*
X0939931Y06875*
X0939807Y0688124*
X0939454Y0688654*
X0938924Y0689007*
X09383Y0689131*
G37*
G36*
X0942941Y0689119D02*
X0942317Y0688995D01*
X0941787Y0688641*
X0941434Y0688112*
X094131Y0687488*
X0941434Y0686863*
X0941787Y0686334*
X0942317Y068598*
X0942941Y0685856*
X0943565Y068598*
X0944094Y0686334*
X0944448Y0686863*
X0944572Y0687488*
X0944448Y0688112*
X0944094Y0688641*
X0943565Y0688995*
X0942941Y0689119*
G37*
G36*
X09545Y0686131D02*
X0953876Y0686007D01*
X0953347Y0685653*
X0952993Y0685124*
X0952869Y06845*
X0952993Y0683876*
X0953347Y0683347*
X0953876Y0682993*
X09545Y0682869*
X0955124Y0682993*
X0955653Y0683347*
X0956007Y0683876*
X0956131Y06845*
X0956007Y0685124*
X0955653Y0685653*
X0955124Y0686007*
X09545Y0686131*
G37*
G36*
X09795Y0686031D02*
X0978876Y0685907D01*
X0978347Y0685554*
X0977993Y0685024*
X0977869Y06844*
X0977993Y0683776*
X0978347Y0683247*
X0978876Y0682893*
X09795Y0682769*
X0980124Y0682893*
X0980653Y0683247*
X0981007Y0683776*
X0981131Y06844*
X0981007Y0685024*
X0980653Y0685554*
X0980124Y0685907*
X09795Y0686031*
G37*
G36*
X12676Y0684831D02*
X1266976Y0684707D01*
X1266446Y0684353*
X1266093Y0683824*
X1265969Y06832*
X1266093Y0682576*
X1266446Y0682047*
X1266976Y0681693*
X12676Y0681569*
X1268224Y0681693*
X1268754Y0682047*
X1269107Y0682576*
X1269231Y06832*
X1269107Y0683824*
X1268754Y0684353*
X1268224Y0684707*
X12676Y0684831*
G37*
G36*
X0931933Y0684631D02*
X0931309Y0684507D01*
X0930779Y0684154*
X0930426Y0683624*
X0930302Y0683*
X0930426Y0682376*
X0930779Y0681847*
X0931309Y0681493*
X0931933Y0681369*
X0932557Y0681493*
X0933086Y0681847*
X093344Y0682376*
X0933564Y0683*
X093344Y0683624*
X0933086Y0684154*
X0932557Y0684507*
X0931933Y0684631*
G37*
G36*
X09935Y0683631D02*
X0992876Y0683507D01*
X0992346Y0683153*
X0991993Y0682624*
X0991869Y0682*
X0991993Y0681376*
X0992346Y0680847*
X0992876Y0680493*
X09935Y0680369*
X0994124Y0680493*
X0994654Y0680847*
X0995007Y0681376*
X0995131Y0682*
X0995007Y0682624*
X0994654Y0683153*
X0994124Y0683507*
X09935Y0683631*
G37*
G36*
X0940462Y0682531D02*
X0939838Y0682407D01*
X0939309Y0682054*
X0938955Y0681524*
X0938831Y06809*
X0938955Y0680276*
X0939309Y0679746*
X0939838Y0679393*
X0940462Y0679269*
X0941087Y0679393*
X0941616Y0679746*
X0941969Y0680276*
X0942094Y06809*
X0941969Y0681524*
X0941616Y0682054*
X0941087Y0682407*
X0940462Y0682531*
G37*
G36*
X09268D02*
X0926176Y0682407D01*
X0925646Y0682054*
X0925293Y0681524*
X0925169Y06809*
X0925293Y0680276*
X0925646Y0679746*
X0926176Y0679393*
X09268Y0679269*
X0927424Y0679393*
X0927954Y0679746*
X0928307Y0680276*
X0928431Y06809*
X0928307Y0681524*
X0927954Y0682054*
X0927424Y0682407*
X09268Y0682531*
G37*
G36*
X10055Y0681631D02*
X1004876Y0681507D01*
X1004346Y0681153*
X1003993Y0680624*
X1003869Y068*
X1003993Y0679376*
X1004346Y0678847*
X1004876Y0678493*
X10055Y0678369*
X1006124Y0678493*
X1006653Y0678847*
X1007007Y0679376*
X1007131Y068*
X1007007Y0680624*
X1006653Y0681153*
X1006124Y0681507*
X10055Y0681631*
G37*
G36*
X12592Y0679731D02*
X1258576Y0679607D01*
X1258047Y0679253*
X1257693Y0678724*
X1257569Y06781*
X1257693Y0677476*
X1258047Y0676946*
X1258576Y0676593*
X12592Y0676469*
X1259824Y0676593*
X1260353Y0676946*
X1260707Y0677476*
X1260831Y06781*
X1260707Y0678724*
X1260353Y0679253*
X1259824Y0679607*
X12592Y0679731*
G37*
G36*
X0971Y0678631D02*
X0970376Y0678507D01*
X0969847Y0678154*
X0969493Y0677624*
X0969369Y0677*
X0969493Y0676376*
X0969847Y0675846*
X0970376Y0675493*
X0971Y0675369*
X0971624Y0675493*
X0972153Y0675846*
X0972507Y0676376*
X0972631Y0677*
X0972507Y0677624*
X0972153Y0678154*
X0971624Y0678507*
X0971Y0678631*
G37*
G36*
X10125Y0677131D02*
X1011876Y0677007D01*
X1011347Y0676653*
X1010993Y0676124*
X1010869Y06755*
X1010993Y0674876*
X1011347Y0674346*
X1011876Y0673993*
X10125Y0673869*
X1013124Y0673993*
X1013653Y0674346*
X1014007Y0674876*
X1014131Y06755*
X1014007Y0676124*
X1013653Y0676653*
X1013124Y0677007*
X10125Y0677131*
G37*
G36*
X12593Y0674231D02*
X1258676Y0674107D01*
X1258146Y0673753*
X1257793Y0673224*
X1257669Y06726*
X1257793Y0671976*
X1258146Y0671447*
X1258676Y0671093*
X12593Y0670969*
X1259924Y0671093*
X1260454Y0671447*
X1260807Y0671976*
X1260931Y06726*
X1260807Y0673224*
X1260454Y0673753*
X1259924Y0674107*
X12593Y0674231*
G37*
G36*
X0918742Y0673431D02*
X0918118Y0673307D01*
X0917589Y0672954*
X0917235Y0672424*
X0917111Y06718*
X0917235Y0671176*
X0917589Y0670646*
X0918118Y0670293*
X0918742Y0670169*
X0919366Y0670293*
X0919896Y0670646*
X0920249Y0671176*
X0920373Y06718*
X0920249Y0672424*
X0919896Y0672954*
X0919366Y0673307*
X0918742Y0673431*
G37*
G36*
X09401Y067339D02*
X0939476Y0673266D01*
X0938947Y0672912*
X0938593Y0672383*
X0938469Y0671759*
X0938593Y0671135*
X0938947Y0670605*
X0939476Y0670252*
X09401Y0670127*
X0940724Y0670252*
X0941253Y0670605*
X0941607Y0671135*
X0941731Y0671759*
X0941607Y0672383*
X0941253Y0672912*
X0940724Y0673266*
X09401Y067339*
G37*
G36*
X09709Y0673331D02*
X0970276Y0673207D01*
X0969746Y0672854*
X0969393Y0672324*
X0969269Y06717*
X0969393Y0671076*
X0969746Y0670546*
X0970276Y0670193*
X09709Y0670069*
X0971524Y0670193*
X0972054Y0670546*
X0972407Y0671076*
X0972531Y06717*
X0972407Y0672324*
X0972054Y0672854*
X0971524Y0673207*
X09709Y0673331*
G37*
G36*
X09987Y0673131D02*
X0998076Y0673007D01*
X0997546Y0672653*
X0997193Y0672124*
X0997069Y06715*
X0997193Y0670876*
X0997546Y0670346*
X0998076Y0669993*
X09987Y0669869*
X0999324Y0669993*
X0999854Y0670346*
X1000207Y0670876*
X1000331Y06715*
X1000207Y0672124*
X0999854Y0672653*
X0999324Y0673007*
X09987Y0673131*
G37*
G36*
X0958D02*
X0957376Y0673007D01*
X0956847Y0672653*
X0956493Y0672124*
X0956369Y06715*
X0956493Y0670876*
X0956847Y0670346*
X0957376Y0669993*
X0958Y0669869*
X0958624Y0669993*
X0959153Y0670346*
X0959507Y0670876*
X0959631Y06715*
X0959507Y0672124*
X0959153Y0672653*
X0958624Y0673007*
X0958Y0673131*
G37*
G36*
X09794Y0671131D02*
X0978776Y0671007D01*
X0978246Y0670653*
X0977893Y0670124*
X0977769Y06695*
X0977893Y0668876*
X0978246Y0668347*
X0978776Y0667993*
X09794Y0667869*
X0980024Y0667993*
X0980554Y0668347*
X0980907Y0668876*
X0981031Y06695*
X0980907Y0670124*
X0980554Y0670653*
X0980024Y0671007*
X09794Y0671131*
G37*
G36*
X09715Y0669531D02*
X0970876Y0669407D01*
X0970347Y0669054*
X0969993Y0668524*
X0969869Y06679*
X0969993Y0667276*
X0970347Y0666747*
X0970876Y0666393*
X09715Y0666269*
X0972124Y0666393*
X0972653Y0666747*
X0973007Y0667276*
X0973131Y06679*
X0973007Y0668524*
X0972653Y0669054*
X0972124Y0669407*
X09715Y0669531*
G37*
G36*
X12593Y0669231D02*
X1258676Y0669107D01*
X1258146Y0668753*
X1257793Y0668224*
X1257669Y06676*
X1257793Y0666976*
X1258146Y0666446*
X1258676Y0666093*
X12593Y0665969*
X1259924Y0666093*
X1260454Y0666446*
X1260807Y0666976*
X1260931Y06676*
X1260807Y0668224*
X1260454Y0668753*
X1259924Y0669107*
X12593Y0669231*
G37*
G36*
X09959Y0669131D02*
X0995276Y0669007D01*
X0994746Y0668653*
X0994393Y0668124*
X0994269Y06675*
X0994393Y0666876*
X0994746Y0666347*
X0995276Y0665993*
X09959Y0665869*
X0996524Y0665993*
X0997054Y0666347*
X0997407Y0666876*
X0997531Y06675*
X0997407Y0668124*
X0997054Y0668653*
X0996524Y0669007*
X09959Y0669131*
G37*
G36*
X0976402Y0668635D02*
X0975778Y0668511D01*
X0975249Y0668157*
X0974895Y0667628*
X0974771Y0667004*
X0974895Y066638*
X0975249Y066585*
X0975778Y0665497*
X0976402Y0665373*
X0977026Y0665497*
X0977556Y066585*
X0977909Y066638*
X0978033Y0667004*
X0977909Y0667628*
X0977556Y0668157*
X0977026Y0668511*
X0976402Y0668635*
G37*
G36*
X09581Y0668231D02*
X0957476Y0668107D01*
X0956946Y0667754*
X0956593Y0667224*
X0956469Y06666*
X0956593Y0665976*
X0956946Y0665447*
X0957476Y0665093*
X09581Y0664969*
X0958724Y0665093*
X0959254Y0665447*
X0959607Y0665976*
X0959731Y06666*
X0959607Y0667224*
X0959254Y0667754*
X0958724Y0668107*
X09581Y0668231*
G37*
G36*
X09215Y066816D02*
X0920876Y0668036D01*
X0920347Y0667682*
X0919993Y0667153*
X0919869Y0666528*
X0919993Y0665904*
X0920347Y0665375*
X0920876Y0665021*
X09215Y0664897*
X0922124Y0665021*
X0922565Y0665316*
X0922974Y0665364*
X0923208Y0665305*
X0923676Y0664993*
X09243Y0664869*
X0924924Y0664993*
X0925453Y0665346*
X0925807Y0665876*
X0925931Y06665*
X0925807Y0667124*
X0925453Y0667654*
X0924924Y0668007*
X09243Y0668131*
X0923676Y0668007*
X0923234Y0667712*
X0922826Y0667665*
X0922592Y0667723*
X0922124Y0668036*
X09215Y066816*
G37*
G36*
X1156831Y0673966D02*
X1155643Y067381D01*
X1154536Y0673351*
X1153586Y0672622*
X1152857Y0671671*
X1152398Y0670565*
X1152242Y0669377*
X1152398Y0668189*
X1152857Y0667082*
X1153586Y0666132*
X1154536Y0665402*
X1155643Y0664944*
X1156831Y0664788*
X1158019Y0664944*
X1159126Y0665402*
X1160076Y0666132*
X1160805Y0667082*
X1161264Y0668189*
X116142Y0669377*
X1161264Y0670565*
X1160805Y0671671*
X1160076Y0672622*
X1159126Y0673351*
X1158019Y067381*
X1156831Y0673966*
G37*
G36*
X12593Y0663231D02*
X1258676Y0663107D01*
X1258146Y0662753*
X1257793Y0662224*
X1257669Y06616*
X1257793Y0660976*
X1258146Y0660447*
X1258676Y0660093*
X12593Y0659969*
X1259924Y0660093*
X1260454Y0660447*
X1260807Y0660976*
X1260931Y06616*
X1260807Y0662224*
X1260454Y0662753*
X1259924Y0663107*
X12593Y0663231*
G37*
G36*
X10122Y0670631D02*
X1011576Y0670507D01*
X1011047Y0670154*
X1010693Y0669624*
X1010569Y0669*
X1010693Y0668376*
X1011047Y0667846*
X1011576Y0667493*
X1011726Y0667463*
X1011766Y0667341*
X1011779Y0666943*
X1011347Y0666653*
X1010993Y0666124*
X1010869Y06655*
X1010993Y0664876*
X1011347Y0664347*
X1011876Y0663993*
X101238Y0663893*
X1012592Y066356*
X1012644Y0663387*
X1012639Y066338*
X1012515Y0662756*
X1012639Y0662132*
X1012993Y0661602*
X1013522Y0661249*
X1014146Y0661125*
X1014771Y0661249*
X1015139Y0661495*
X10155Y0661135*
X1015493Y0661124*
X1015369Y06605*
X1015493Y0659876*
X1015847Y0659346*
X1016376Y0658993*
X1017Y0658869*
X1017624Y0658993*
X1018153Y0659346*
X1018507Y0659876*
X1018631Y06605*
X1018507Y0661124*
X1018153Y0661654*
X1017624Y0662007*
X1017Y0662131*
X1016376Y0662007*
X1016007Y0661761*
X1015647Y0662121*
X1015654Y0662132*
X1015778Y0662756*
X1015654Y066338*
X10153Y066391*
X1014771Y0664263*
X1014266Y0664363*
X1014054Y0664696*
X1014002Y0664868*
X1014007Y0664876*
X1014131Y06655*
X1014007Y0666124*
X1013653Y0666653*
X1013124Y0667007*
X1012974Y0667037*
X1012934Y0667159*
X1012921Y0667557*
X1013354Y0667846*
X1013707Y0668376*
X1013831Y0669*
X1013707Y0669624*
X1013354Y0670154*
X1012824Y0670507*
X10122Y0670631*
G37*
G36*
X09404Y0659331D02*
X0939776Y0659207D01*
X0939246Y0658853*
X0938893Y0658324*
X0938769Y06577*
X0938893Y0657076*
X0939246Y0656546*
X0939776Y0656193*
X09404Y0656069*
X0941024Y0656193*
X0941553Y0656546*
X0941907Y0657076*
X0942031Y06577*
X0941907Y0658324*
X0941553Y0658853*
X0941024Y0659207*
X09404Y0659331*
G37*
G36*
X09885Y0658631D02*
X0987876Y0658507D01*
X0987346Y0658153*
X0986993Y0657624*
X0986869Y0657*
X0986993Y0656376*
X0987346Y0655847*
X0987876Y0655493*
X09885Y0655369*
X0989124Y0655493*
X0989653Y0655847*
X0990007Y0656376*
X0990131Y0657*
X0990007Y0657624*
X0989653Y0658153*
X0989124Y0658507*
X09885Y0658631*
G37*
G36*
X0996Y0657231D02*
X0995376Y0657107D01*
X0994847Y0656753*
X0994493Y0656224*
X0994369Y06556*
X0994493Y0654976*
X0994847Y0654447*
X0995376Y0654093*
X0996Y0653969*
X0996624Y0654093*
X0996825Y0654227*
X0997327Y0654342*
X0997583Y0654189*
X0997876Y0653993*
X09985Y0653869*
X0999124Y0653993*
X0999654Y0654347*
X1000007Y0654876*
X1000131Y06555*
X1000007Y0656124*
X0999654Y0656653*
X0999124Y0657007*
X09985Y0657131*
X0997876Y0657007*
X0997346Y0656653*
X099722*
X0997153Y0656753*
X0996624Y0657107*
X0996Y0657231*
G37*
G36*
X10025Y0656631D02*
X1001876Y0656507D01*
X1001346Y0656153*
X1000993Y0655624*
X1000869Y0655*
X1000993Y0654376*
X1001346Y0653847*
X1001876Y0653493*
X10025Y0653369*
X1003124Y0653493*
X1003654Y0653847*
X1004007Y0654376*
X1004131Y0655*
X1004007Y0655624*
X1003654Y0656153*
X1003124Y0656507*
X10025Y0656631*
G37*
G36*
X09915Y0655631D02*
X0990876Y0655507D01*
X0990347Y0655154*
X0989993Y0654624*
X0989869Y0654*
X0989993Y0653376*
X0990347Y0652846*
X0990876Y0652493*
X09915Y0652369*
X0992124Y0652493*
X0992653Y0652846*
X0993007Y0653376*
X0993131Y0654*
X0993007Y0654624*
X0992653Y0655154*
X0992124Y0655507*
X09915Y0655631*
G37*
G36*
X08885Y0658131D02*
X0887876Y0658007D01*
X0887346Y0657654*
X0886993Y0657124*
X0886869Y06565*
X0886993Y0655876*
X0887346Y0655346*
X0887876Y0654993*
X08885Y0654869*
X0889124Y0654993*
X0889149Y0655009*
X0889509Y0654649*
X0889493Y0654624*
X0889369Y0654*
X0889493Y0653376*
X0889847Y0652846*
X0890376Y0652493*
X0891Y0652369*
X0891624Y0652493*
X0892153Y0652846*
X0892507Y0653376*
X0892631Y0654*
X0892507Y0654624*
X0892153Y0655154*
X0891624Y0655507*
X0891Y0655631*
X0890376Y0655507*
X0890351Y0655491*
X0889991Y0655851*
X0890007Y0655876*
X0890131Y06565*
X0890007Y0657124*
X0889653Y0657654*
X0889124Y0658007*
X08885Y0658131*
G37*
G36*
X12539Y0655131D02*
X1253276Y0655007D01*
X1252746Y0654654*
X1252393Y0654124*
X1252269Y06535*
X1252393Y0652876*
X1252746Y0652347*
X1253276Y0651993*
X12539Y0651869*
X1254524Y0651993*
X1255054Y0652347*
X1255407Y0652876*
X1255531Y06535*
X1255407Y0654124*
X1255054Y0654654*
X1254524Y0655007*
X12539Y0655131*
G37*
G36*
X09585Y0653431D02*
X0957876Y0653307D01*
X0957347Y0652953*
X0956993Y0652424*
X0956869Y06518*
X0956993Y0651176*
X0957347Y0650646*
X0957876Y0650293*
X09585Y0650169*
X0959124Y0650293*
X0959653Y0650646*
X0960007Y0651176*
X0960131Y06518*
X0960007Y0652424*
X0959653Y0652953*
X0959124Y0653307*
X09585Y0653431*
G37*
G36*
X10055Y0653131D02*
X1004876Y0653007D01*
X1004346Y0652654*
X1003993Y0652124*
X1003869Y06515*
X1003993Y0650876*
X1004346Y0650347*
X1004876Y0649993*
X10055Y0649869*
X1006124Y0649993*
X1006653Y0650347*
X1007007Y0650876*
X1007131Y06515*
X1007007Y0652124*
X1006653Y0652654*
X1006124Y0653007*
X10055Y0653131*
G37*
G36*
X09855D02*
X0984876Y0653007D01*
X0984346Y0652654*
X0983993Y0652124*
X0983869Y06515*
X0983993Y0650876*
X0984346Y0650347*
X0984876Y0649993*
X09855Y0649869*
X0986124Y0649993*
X0986654Y0650347*
X0987007Y0650876*
X0987131Y06515*
X0987007Y0652124*
X0986654Y0652654*
X0986124Y0653007*
X09855Y0653131*
G37*
G36*
X09825Y0650131D02*
X0981876Y0650007D01*
X0981347Y0649653*
X0980993Y0649124*
X0980869Y06485*
X0980993Y0647876*
X0981347Y0647346*
X0981876Y0646993*
X09825Y0646869*
X0983124Y0646993*
X0983654Y0647346*
X0984007Y0647876*
X0984131Y06485*
X0984007Y0649124*
X0983654Y0649653*
X0983124Y0650007*
X09825Y0650131*
G37*
G36*
X09397Y0648131D02*
X0939076Y0648007D01*
X0938546Y0647653*
X0938193Y0647124*
X0938069Y06465*
X0938193Y0645876*
X0938546Y0645346*
X0939076Y0644993*
X09397Y0644869*
X0940324Y0644993*
X0940854Y0645346*
X0941207Y0645876*
X0941331Y06465*
X0941207Y0647124*
X0940854Y0647653*
X0940324Y0648007*
X09397Y0648131*
G37*
G36*
X09723Y0643831D02*
X0971676Y0643707D01*
X0971146Y0643354*
X0970793Y0642824*
X0970669Y06422*
X0970793Y0641576*
X0971146Y0641046*
X0971676Y0640693*
X09723Y0640569*
X0972924Y0640693*
X0973454Y0641046*
X0973807Y0641576*
X0973931Y06422*
X0973807Y0642824*
X0973454Y0643354*
X0972924Y0643707*
X09723Y0643831*
G37*
G36*
X0939744Y0643157D02*
X093912Y0643033D01*
X093859Y064268*
X0938237Y064215*
X0938113Y0641526*
X0938237Y0640902*
X0938536Y0640453*
X0938153Y0640154*
X0937624Y0640507*
X0937Y0640631*
X0936376Y0640507*
X0935847Y0640154*
X0935493Y0639624*
X0935369Y0639*
X0935493Y0638376*
X0935847Y0637847*
X0936376Y0637493*
X0937Y0637369*
X0937518Y0637472*
X0937822Y0637254*
X0937944Y0637105*
X0937869Y0636726*
X0937993Y0636102*
X0938218Y0635764*
X0938282Y0635669*
X0937921Y0635309*
X0937844Y063536*
X0937624Y0635507*
X0937Y0635631*
X0936376Y0635507*
X0935847Y0635153*
X0935493Y0634624*
X0935369Y0634*
X0935493Y0633376*
X0935847Y0632846*
X0936376Y0632493*
X0937Y0632369*
X0937624Y0632493*
X0938153Y0632846*
X0938507Y0633376*
X0938631Y0634*
X0938507Y0634624*
X0938282Y0634962*
X0938218Y0635057*
X0938579Y0635417*
X0938656Y0635366*
X0938876Y0635219*
X09395Y0635095*
X0940124Y0635219*
X0940654Y0635572*
X0941007Y0636102*
X0941131Y0636726*
X0941007Y063735*
X0940654Y063788*
X0940124Y0638233*
X09395Y0638357*
X0938982Y0638254*
X0938678Y0638472*
X0938556Y0638621*
X0938631Y0639*
X0938507Y0639624*
X0938208Y0640073*
X093859Y0640372*
X093912Y0640019*
X0939744Y0639895*
X0940368Y0640019*
X0940897Y0640373*
X0941251Y0640902*
X0941375Y0641526*
X0941251Y064215*
X0940897Y064268*
X0940368Y0643033*
X0939744Y0643157*
G37*
G36*
X0954Y0646131D02*
X0953376Y0646007D01*
X0952847Y0645653*
X0952493Y0645124*
X0952369Y06445*
X0952493Y0643876*
X0952847Y0643347*
Y0642853*
X0952493Y0642324*
X0952369Y06417*
X0952493Y0641076*
X0952847Y0640547*
X0953376Y0640193*
X0954Y0640069*
X0954624Y0640193*
X0955153Y0640547*
X0955507Y0641076*
X0955631Y06417*
X0955507Y0642324*
X0955153Y0642853*
Y0643347*
X0955507Y0643876*
X0955631Y06445*
X0955507Y0645124*
X0955153Y0645653*
X0954624Y0646007*
X0954Y0646131*
G37*
G36*
X095619Y0633293D02*
X0955455Y0633147D01*
X0954832Y0632731*
X0954416Y0632108*
X095427Y0631373*
X0954416Y0630638*
X0954832Y0630015*
X0955455Y0629599*
X095619Y0629453*
X0956925Y0629599*
X0957548Y0630015*
X0957964Y0630638*
X095811Y0631373*
X0957964Y0632108*
X0957548Y0632731*
X0956925Y0633147*
X095619Y0633293*
G37*
G36*
X096081Y0598761D02*
X0959496Y0598631D01*
X0958232Y0598248*
X0957067Y0597625*
X0956046Y0596787*
X0955208Y0595766*
X0954585Y0594601*
X0954202Y0593337*
X0954072Y0592023*
X0954202Y0590708*
X0954585Y0589444*
X0955208Y058828*
X0956046Y0587259*
X0957067Y0586421*
X0958232Y0585798*
X0959496Y0585415*
X096081Y0585285*
X0962125Y0585415*
X0963389Y0585798*
X0964553Y0586421*
X0965574Y0587259*
X0966412Y058828*
X0967035Y0589444*
X0967418Y0590708*
X0967548Y0592023*
X0967418Y0593337*
X0967035Y0594601*
X0966412Y0595766*
X0965574Y0596787*
X0964553Y0597625*
X0963389Y0598248*
X0962125Y0598631*
X096081Y0598761*
G37*
G36*
X1156831Y0594045D02*
X1155643Y0593888D01*
X1154536Y059343*
X1153586Y0592701*
X1152857Y059175*
X1152398Y0590643*
X1152242Y0589456*
X1152398Y0588268*
X1152857Y0587161*
X1153586Y058621*
X1154536Y0585481*
X1155643Y0585023*
X1156831Y0584866*
X1158019Y0585023*
X1159126Y0585481*
X1160076Y058621*
X1160805Y0587161*
X1161264Y0588268*
X116142Y0589456*
X1161264Y0590643*
X1160805Y059175*
X1160076Y0592701*
X1159126Y059343*
X1158019Y0593888*
X1156831Y0594045*
G37*
G36*
X09386Y0924231D02*
X0937976Y0924107D01*
X0937446Y0923754*
X0937093Y0923224*
X0936969Y09226*
X0937093Y0921976*
X0937446Y0921447*
X0937976Y0921093*
X09386Y0920969*
X0939224Y0921093*
X0939754Y0921447*
X0940107Y0921976*
X0940231Y09226*
X0940107Y0923224*
X0939754Y0923754*
X0939224Y0924107*
X09386Y0924231*
G37*
G36*
X08879Y0924131D02*
X0887276Y0924007D01*
X0886747Y0923654*
X0886393Y0923124*
X0886269Y09225*
X0886393Y0921876*
X0886747Y0921346*
X0887276Y0920993*
X08879Y0920869*
X0888524Y0920993*
X0889054Y0921346*
X0889407Y0921876*
X0889531Y09225*
X0889407Y0923124*
X0889054Y0923654*
X0888524Y0924007*
X08879Y0924131*
G37*
G36*
X08281Y0923731D02*
X0827476Y0923607D01*
X0826947Y0923254*
X0826593Y0922724*
X0826469Y09221*
X0826593Y0921476*
X0826947Y0920947*
X0827476Y0920593*
X08281Y0920469*
X0828724Y0920593*
X0829253Y0920947*
X0829607Y0921476*
X0829731Y09221*
X0829607Y0922724*
X0829253Y0923254*
X0828724Y0923607*
X08281Y0923731*
G37*
G36*
X10378Y0922631D02*
X1037176Y0922507D01*
X1036646Y0922153*
X1036293Y0921624*
X1036169Y0921*
X1036293Y0920376*
X1036646Y0919847*
X1037176Y0919493*
X10378Y0919369*
X1038424Y0919493*
X1038953Y0919847*
X1039307Y0920376*
X1039431Y0921*
X1039307Y0921624*
X1038953Y0922153*
X1038424Y0922507*
X10378Y0922631*
G37*
G36*
X10901Y0922331D02*
X1089476Y0922207D01*
X1088947Y0921854*
X1088593Y0921324*
X1088469Y09207*
X1088593Y0920076*
X1088947Y0919547*
X1089476Y0919193*
X10901Y0919069*
X1090724Y0919193*
X1091253Y0919547*
X1091607Y0920076*
X1091731Y09207*
X1091607Y0921324*
X1091253Y0921854*
X1090724Y0922207*
X10901Y0922331*
G37*
G36*
X0994823Y0915594D02*
X0994151Y0915506D01*
X0993526Y0915246*
X0992989Y0914834*
X0992577Y0914297*
X0992317Y0913671*
X0992229Y0913*
X0992317Y0912329*
X0992577Y0911703*
X0992989Y0911166*
X0993526Y0910754*
X0994151Y0910495*
X0994823Y0910406*
X0995494Y0910495*
X099612Y0910754*
X0996657Y0911166*
X0997069Y0911703*
X0997328Y0912329*
X0997417Y0913*
X0997328Y0913671*
X0997069Y0914297*
X0996657Y0914834*
X099612Y0915246*
X0995494Y0915506*
X0994823Y0915594*
G37*
G36*
X09775D02*
X0976829Y0915506D01*
X0976203Y0915246*
X0975666Y0914834*
X0975254Y0914297*
X0974994Y0913671*
X0974906Y0913*
X0974994Y0912329*
X0975254Y0911703*
X0975666Y0911166*
X0976203Y0910754*
X0976829Y0910495*
X09775Y0910406*
X0978171Y0910495*
X0978797Y0910754*
X0979334Y0911166*
X0979746Y0911703*
X0980005Y0912329*
X0980094Y0913*
X0980005Y0913671*
X0979746Y0914297*
X0979334Y0914834*
X0978797Y0915246*
X0978171Y0915506*
X09775Y0915594*
G37*
G36*
X1074487Y0913618D02*
X1073863Y0913494D01*
X1073333Y091314*
X107298Y0912611*
X1072856Y0911987*
X107298Y0911363*
X1073333Y0910833*
X1073863Y091048*
X1074487Y0910356*
X1075111Y091048*
X107564Y0910833*
X1075994Y0911363*
X1076118Y0911987*
X1075994Y0912611*
X107564Y091314*
X1075111Y0913494*
X1074487Y0913618*
G37*
G36*
X117122Y0919881D02*
X1169727Y0919684D01*
X1168335Y0919108*
X116714Y0918191*
X1166223Y0916996*
X1165646Y0915604*
X116545Y091411*
X1165646Y0912617*
X1166223Y0911225*
X116714Y091003*
X1168335Y0909113*
X1169727Y0908536*
X117122Y090834*
X1172714Y0908536*
X1174106Y0909113*
X1175301Y091003*
X1176218Y0911225*
X1176795Y0912617*
X1176991Y091411*
X1176795Y0915604*
X1176218Y0916996*
X1175301Y0918191*
X1174106Y0919108*
X1172714Y0919684*
X117122Y0919881*
G37*
G36*
X1125716Y0910915D02*
X1125092Y0910791D01*
X1124563Y0910437*
X1124209Y0909908*
X1124085Y0909284*
X1124209Y0908659*
X1124563Y090813*
X1125092Y0907776*
X1125716Y0907652*
X1126341Y0907776*
X112687Y090813*
X1127224Y0908659*
X1127348Y0909284*
X1127224Y0909908*
X112687Y0910437*
X1126341Y0910791*
X1125716Y0910915*
G37*
G36*
X09495Y0910631D02*
X0948876Y0910507D01*
X0948347Y0910153*
X0947993Y0909624*
X0947869Y0909*
X0947993Y0908376*
X0948347Y0907847*
X0948876Y0907493*
X09495Y0907369*
X0950124Y0907493*
X0950653Y0907847*
X0951007Y0908376*
X0951131Y0909*
X0951007Y0909624*
X0950653Y0910153*
X0950124Y0910507*
X09495Y0910631*
G37*
G36*
X09285Y0913138D02*
X092743Y0912998D01*
X0926433Y0912585*
X0925576Y0911928*
X0924919Y0911071*
X0924506Y0910074*
X0924365Y0909004*
X0924506Y0907934*
X0924919Y0906937*
X0925576Y090608*
X0926433Y0905423*
X092743Y090501*
X09285Y0904869*
X092957Y090501*
X0930567Y0905423*
X0931424Y090608*
X0932081Y0906937*
X0932494Y0907934*
X0932635Y0909004*
X0932494Y0910074*
X0932081Y0911071*
X0931424Y0911928*
X0930567Y0912585*
X092957Y0912998*
X09285Y0913138*
G37*
G36*
X08985D02*
X089743Y0912998D01*
X0896433Y0912585*
X0895576Y0911928*
X0894919Y0911071*
X0894506Y0910074*
X0894365Y0909004*
X0894506Y0907934*
X0894919Y0906937*
X0895576Y090608*
X0896433Y0905423*
X089743Y090501*
X08985Y0904869*
X089957Y090501*
X0900567Y0905423*
X0901424Y090608*
X0902081Y0906937*
X0902494Y0907934*
X0902635Y0909004*
X0902494Y0910074*
X0902081Y0911071*
X0901424Y0911928*
X0900567Y0912585*
X089957Y0912998*
X08985Y0913138*
G37*
G36*
X09768Y0904331D02*
X0976176Y0904207D01*
X0975646Y0903854*
X0975293Y0903324*
X0975169Y09027*
X0975293Y0902076*
X0975646Y0901546*
X0976176Y0901193*
X09768Y0901069*
X0977424Y0901193*
X0977954Y0901546*
X0978307Y0902076*
X0978431Y09027*
X0978307Y0903324*
X0977954Y0903854*
X0977424Y0904207*
X09768Y0904331*
G37*
G36*
X1215429Y0911274D02*
X1206571D01*
X1205206Y0911094*
X1203934Y0910568*
X1202841Y0909729*
X1202003Y0908637*
X1201476Y0907365*
X1201297Y0906*
X1201476Y0904635*
X1202003Y0903363*
X1202841Y0902271*
X1203934Y0901432*
X1205206Y0900906*
X1206571Y0900726*
X1215429*
X1216794Y0900906*
X1218066Y0901432*
X1219159Y0902271*
X1219997Y0903363*
X1220524Y0904635*
X1220703Y0906*
X1220524Y0907365*
X1219997Y0908637*
X1219159Y0909729*
X1218066Y0910568*
X1216794Y0911094*
X1215429Y0911274*
G37*
G36*
X08235Y0903731D02*
X0822876Y0903607D01*
X0822346Y0903253*
X0821993Y0902724*
X0821869Y09021*
X0821993Y0901476*
X0822346Y0900947*
X0822876Y0900593*
X08235Y0900469*
X0824124Y0900593*
X0824654Y0900947*
X0825007Y0901476*
X0825131Y09021*
X0825007Y0902724*
X0824654Y0903253*
X0824124Y0903607*
X08235Y0903731*
G37*
G36*
X117122Y0901771D02*
X1169727Y0901574D01*
X1168335Y0900998*
X116714Y090008*
X1166223Y0898885*
X1165646Y0897493*
X116545Y0896*
X1165646Y0894506*
X1166223Y0893115*
X116714Y089192*
X1168335Y0891002*
X1169727Y0890426*
X117122Y0890229*
X1172714Y0890426*
X1174106Y0891002*
X1175301Y089192*
X1176218Y0893115*
X1176795Y0894506*
X1176991Y0896*
X1176795Y0897493*
X1176218Y0898885*
X1175301Y090008*
X1174106Y0900998*
X1172714Y0901574*
X117122Y0901771*
G37*
G36*
X08075Y0891631D02*
X0806876Y0891507D01*
X0806347Y0891154*
X0805993Y0890624*
X0805869Y089*
X0805993Y0889376*
X0806009Y0889351*
X0805649Y0888991*
X0805624Y0889007*
X0805Y0889131*
X0804376Y0889007*
X0803846Y0888653*
X0803493Y0888124*
X0803369Y08875*
X0803493Y0886876*
X0803846Y0886347*
X0804376Y0885993*
X0805Y0885869*
X0805624Y0885993*
X0806153Y0886347*
X0806507Y0886876*
X0806631Y08875*
X0806507Y0888124*
X0806491Y0888149*
X0806851Y0888509*
X0806876Y0888493*
X08075Y0888369*
X0808124Y0888493*
X0808654Y0888846*
X0809007Y0889376*
X0809131Y089*
X0809007Y0890624*
X0808654Y0891154*
X0808124Y0891507*
X08075Y0891631*
G37*
G36*
X1192496Y0903892D02*
X1191131Y0903713D01*
X1189859Y0903186*
X1188767Y0902348*
X1187928Y0901255*
X1187401Y0899983*
X1187222Y0898618*
Y088976*
X1187401Y0888395*
X1187928Y0887123*
X1188767Y088603*
X1189859Y0885192*
X1191131Y0884665*
X1192496Y0884486*
X1193861Y0884665*
X1195133Y0885192*
X1196225Y088603*
X1197064Y0887123*
X1197591Y0888395*
X119777Y088976*
Y0898618*
X1197591Y0899983*
X1197064Y0901255*
X1196225Y0902348*
X1195133Y0903186*
X1193861Y0903713*
X1192496Y0903892*
G37*
G36*
X0969Y0885631D02*
X0968376Y0885507D01*
X0967846Y0885153*
X0967493Y0884624*
X0967369Y0884*
X0967493Y0883376*
X0967846Y0882847*
X0968376Y0882493*
X0969Y0882369*
X0969624Y0882493*
X0970154Y0882847*
X0970507Y0883376*
X0970631Y0884*
X0970507Y0884624*
X0970154Y0885153*
X0969624Y0885507*
X0969Y0885631*
G37*
G36*
X09005Y0885131D02*
X0899876Y0885007D01*
X0899347Y0884653*
X0898993Y0884124*
X0898869Y08835*
X0898993Y0882876*
X0899347Y0882347*
X0899876Y0881993*
X09005Y0881869*
X0901124Y0881993*
X0901653Y0882347*
X0902007Y0882876*
X0902131Y08835*
X0902007Y0884124*
X0901653Y0884653*
X0901124Y0885007*
X09005Y0885131*
G37*
G36*
X0926Y0880831D02*
X0925376Y0880707D01*
X0924846Y0880354*
X0924493Y0879824*
X0924369Y08792*
X0924493Y0878576*
X0924846Y0878047*
X0925376Y0877693*
X0926Y0877569*
X0926624Y0877693*
X0927153Y0878047*
X0927507Y0878576*
X0927631Y08792*
X0927507Y0879824*
X0927153Y0880354*
X0926624Y0880707*
X0926Y0880831*
G37*
G36*
X08851Y0880731D02*
X0884476Y0880607D01*
X0883947Y0880254*
X0883593Y0879724*
X0883469Y08791*
X0883593Y0878476*
X0883947Y0877946*
X0884476Y0877593*
X08851Y0877469*
X0885724Y0877593*
X0886254Y0877946*
X0886607Y0878476*
X0886731Y08791*
X0886607Y0879724*
X0886254Y0880254*
X0885724Y0880607*
X08851Y0880731*
G37*
G36*
X1215921Y0888149D02*
X1206079D01*
X1204585Y0887952*
X1203193Y0887376*
X1201998Y0886458*
X1201081Y0885263*
X1200505Y0883871*
X1200308Y0882378*
X1200505Y0880884*
X1201081Y0879493*
X1201998Y0878298*
X1203193Y087738*
X1204585Y0876804*
X1206079Y0876607*
X1215921*
X1217415Y0876804*
X1218807Y087738*
X1220002Y0878298*
X1220919Y0879493*
X1221495Y0880884*
X1221692Y0882378*
X1221495Y0883871*
X1220919Y0885263*
X1220002Y0886458*
X1218807Y0887376*
X1217415Y0887952*
X1215921Y0888149*
G37*
G36*
X09821Y0878231D02*
X0981476Y0878107D01*
X0980947Y0877754*
X0980593Y0877224*
X0980469Y08766*
X0980593Y0875976*
X0980947Y0875447*
X0981476Y0875093*
X09821Y0874969*
X0982724Y0875093*
X0983253Y0875447*
X0983607Y0875976*
X0983731Y08766*
X0983607Y0877224*
X0983253Y0877754*
X0982724Y0878107*
X09821Y0878231*
G37*
G36*
X0969Y0877131D02*
X0968376Y0877007D01*
X0967846Y0876653*
X0967493Y0876124*
X0967369Y08755*
X0967493Y0874876*
X0967846Y0874347*
X0968376Y0873993*
X0969Y0873869*
X0969624Y0873993*
X0970154Y0874347*
X0970507Y0874876*
X0970631Y08755*
X0970507Y0876124*
X0970154Y0876653*
X0969624Y0877007*
X0969Y0877131*
G37*
G36*
X0898354D02*
X089773Y0877007D01*
X0897201Y0876653*
X0896847Y0876124*
X0896723Y08755*
X0896847Y0874876*
X0897201Y0874347*
X089773Y0873993*
X0898354Y0873869*
X0898979Y0873993*
X0899508Y0874347*
X0899862Y0874876*
X0899986Y08755*
X0899862Y0876124*
X0899508Y0876653*
X0898979Y0877007*
X0898354Y0877131*
G37*
G36*
X08249Y0876131D02*
X0824276Y0876007D01*
X0823746Y0875653*
X0823393Y0875124*
X0823269Y08745*
X0823393Y0873876*
X0823746Y0873347*
X0824276Y0872993*
X08249Y0872869*
X0825524Y0872993*
X0826054Y0873347*
X0826407Y0873876*
X0826531Y08745*
X0826407Y0875124*
X0826054Y0875653*
X0825524Y0876007*
X08249Y0876131*
G37*
G36*
X0813Y0875831D02*
X0812376Y0875707D01*
X0811847Y0875354*
X0811493Y0874824*
X0811369Y08742*
X0811493Y0873576*
X0811847Y0873046*
X0812376Y0872693*
X0813Y0872569*
X0813624Y0872693*
X0814153Y0873046*
X0814507Y0873576*
X0814631Y08742*
X0814507Y0874824*
X0814153Y0875354*
X0813624Y0875707*
X0813Y0875831*
G37*
G36*
X08715Y0874931D02*
X0870876Y0874807D01*
X0870347Y0874454*
X0869993Y0873924*
X0869869Y08733*
X0869993Y0872676*
X0870347Y0872147*
X0870876Y0871793*
X08715Y0871669*
X0872124Y0871793*
X0872653Y0872147*
X0873007Y0872676*
X0873131Y08733*
X0873007Y0873924*
X0872653Y0874454*
X0872124Y0874807*
X08715Y0874931*
G37*
G36*
X1066Y0862631D02*
X1065376Y0862507D01*
X1064847Y0862154*
X1064493Y0861624*
X1064369Y0861*
X1064493Y0860376*
X1064847Y0859846*
X1065376Y0859493*
X1066Y0859369*
X1066624Y0859493*
X1067153Y0859846*
X1067507Y0860376*
X1067631Y0861*
X1067507Y0861624*
X1067153Y0862154*
X1066624Y0862507*
X1066Y0862631*
G37*
G36*
X084075Y0863026D02*
X0839854Y0862848D01*
X0839095Y086234*
X0838587Y0861581*
X0838409Y0860685*
X0838587Y0859789*
X0839095Y085903*
X0839854Y0858522*
X084075Y0858344*
X0841646Y0858522*
X0842405Y085903*
X0842913Y0859789*
X0843091Y0860685*
X0842913Y0861581*
X0842405Y086234*
X0841646Y0862848*
X084075Y0863026*
G37*
G36*
X11724Y0857631D02*
X1171776Y0857507D01*
X1171247Y0857154*
X1170893Y0856624*
X1170769Y0856*
X1170893Y0855376*
X1171247Y0854846*
X1171776Y0854493*
X11724Y0854369*
X1173024Y0854493*
X1173553Y0854846*
X1173907Y0855376*
X1174031Y0856*
X1173907Y0856624*
X1173553Y0857154*
X1173024Y0857507*
X11724Y0857631*
G37*
G36*
X11667Y0856631D02*
X1166076Y0856507D01*
X1165547Y0856153*
X1165193Y0855624*
X1165069Y0855*
X1165193Y0854376*
X1165547Y0853846*
X1166076Y0853493*
X11667Y0853369*
X1167324Y0853493*
X1167854Y0853846*
X1168207Y0854376*
X1168331Y0855*
X1168207Y0855624*
X1167854Y0856153*
X1167324Y0856507*
X11667Y0856631*
G37*
G36*
X08425D02*
X0841876Y0856507D01*
X0841346Y0856153*
X0840993Y0855624*
X0840869Y0855*
X0840993Y0854376*
X0841346Y0853846*
X0841876Y0853493*
X08425Y0853369*
X0843124Y0853493*
X0843653Y0853846*
X0844007Y0854376*
X0844131Y0855*
X0844007Y0855624*
X0843653Y0856153*
X0843124Y0856507*
X08425Y0856631*
G37*
G36*
X08245Y0855631D02*
X0823876Y0855507D01*
X0823347Y0855153*
X0822993Y0854624*
X0822869Y0854*
X0822993Y0853376*
X0823265Y0852969*
X082298Y0852536*
X08225Y0852631*
X0821876Y0852507*
X0821346Y0852153*
X0820993Y0851624*
X0820869Y0851*
X0820993Y0850376*
X0821346Y0849846*
X0821876Y0849493*
X08225Y0849369*
X0823124Y0849493*
X0823654Y0849846*
X0824007Y0850376*
X0824131Y0851*
X0824007Y0851624*
X0823735Y0852031*
X082402Y0852464*
X08245Y0852369*
X0825124Y0852493*
X0825653Y0852847*
X0826007Y0853376*
X0826131Y0854*
X0826007Y0854624*
X0825653Y0855153*
X0825124Y0855507*
X08245Y0855631*
G37*
G36*
X0838Y0850131D02*
X0837376Y0850007D01*
X0836847Y0849654*
X0836493Y0849124*
X0836369Y08485*
X0836493Y0847876*
X0836847Y0847346*
X0837376Y0846993*
X0838Y0846869*
X0838624Y0846993*
X0839153Y0847346*
X0839507Y0847876*
X0839631Y08485*
X0839507Y0849124*
X0839153Y0849654*
X0838624Y0850007*
X0838Y0850131*
G37*
G36*
X084075Y0847278D02*
X0839854Y08471D01*
X0839095Y0846592*
X0838587Y0845833*
X0838409Y0844937*
X0838587Y0844041*
X0839095Y0843282*
X0839854Y0842774*
X084075Y0842596*
X0841646Y0842774*
X0842405Y0843282*
X0842913Y0844041*
X0843091Y0844937*
X0842913Y0845833*
X0842405Y0846592*
X0841646Y08471*
X084075Y0847278*
G37*
G36*
X0832Y0838131D02*
X0831376Y0838007D01*
X0830847Y0837654*
X0830493Y0837124*
X0830369Y08365*
X0830493Y0835876*
X0830847Y0835347*
X0831376Y0834993*
X0832Y0834869*
X0832624Y0834993*
X0833154Y0835347*
X0833507Y0835876*
X0833631Y08365*
X0833507Y0837124*
X0833154Y0837654*
X0832624Y0838007*
X0832Y0838131*
G37*
G36*
X0825Y0828131D02*
X0824376Y0828007D01*
X0823847Y0827654*
X0823493Y0827124*
X0823369Y08265*
X0823493Y0825876*
X0823847Y0825346*
X0824376Y0824993*
X0825Y0824869*
X0825624Y0824993*
X0826153Y0825346*
X0826507Y0825876*
X0826631Y08265*
X0826507Y0827124*
X0826153Y0827654*
X0825624Y0828007*
X0825Y0828131*
G37*
G36*
X08196Y0822031D02*
X0818976Y0821907D01*
X0818447Y0821554*
X0818093Y0821024*
X0817969Y08204*
X0818093Y0819776*
X0818447Y0819246*
X0818976Y0818893*
X08196Y0818769*
X0820224Y0818893*
X0820753Y0819246*
X0821107Y0819776*
X0821231Y08204*
X0821107Y0821024*
X0820753Y0821554*
X0820224Y0821907*
X08196Y0822031*
G37*
G36*
X10468Y0815531D02*
X1046176Y0815407D01*
X1045646Y0815053*
X1045293Y0814524*
X1045169Y08139*
X1045293Y0813276*
X1045646Y0812747*
X1046176Y0812393*
X10468Y0812269*
X1047424Y0812393*
X1047954Y0812747*
X1048307Y0813276*
X1048431Y08139*
X1048307Y0814524*
X1047954Y0815053*
X1047424Y0815407*
X10468Y0815531*
G37*
G36*
X10422D02*
X1041576Y0815407D01*
X1041047Y0815053*
X1040693Y0814524*
X1040569Y08139*
X1040693Y0813276*
X1041047Y0812747*
X1041576Y0812393*
X10422Y0812269*
X1042824Y0812393*
X1043353Y0812747*
X1043707Y0813276*
X1043831Y08139*
X1043707Y0814524*
X1043353Y0815053*
X1042824Y0815407*
X10422Y0815531*
G37*
G36*
X1085Y0801631D02*
X1084376Y0801507D01*
X1083846Y0801153*
X1083493Y0800624*
X1083369Y08*
X1083493Y0799376*
X1083846Y0798846*
X1084376Y0798493*
X1085Y0798369*
X1085624Y0798493*
X1086154Y0798846*
X1086507Y0799376*
X1086631Y08*
X1086507Y0800624*
X1086154Y0801153*
X1085624Y0801507*
X1085Y0801631*
G37*
G36*
X1224409Y079297D02*
X1223785Y0792846D01*
X1223256Y0792492*
X1222902Y0791963*
X1222778Y0791339*
X1222902Y0790714*
X1223256Y0790185*
X1223785Y0789831*
X1224409Y0789707*
X1225034Y0789831*
X1225563Y0790185*
X1225917Y0790714*
X1226041Y0791339*
X1225917Y0791963*
X1225563Y0792492*
X1225034Y0792846*
X1224409Y079297*
G37*
G36*
X1156831Y0753887D02*
X1155643Y0753731D01*
X1154536Y0753272*
X1153586Y0752543*
X1152857Y0751593*
X1152398Y0750486*
X1152242Y0749298*
X1152398Y074811*
X1152857Y0747003*
X1153586Y0746053*
X1154536Y0745324*
X1155643Y0744865*
X1156831Y0744709*
X1158019Y0744865*
X1159126Y0745324*
X1160076Y0746053*
X1160805Y0747003*
X1161264Y074811*
X116142Y0749298*
X1161264Y0750486*
X1160805Y0751593*
X1160076Y0752543*
X1159126Y0753272*
X1158019Y0753731*
X1156831Y0753887*
G37*
G36*
X11995Y0745431D02*
X1198876Y0745307D01*
X1198347Y0744953*
X1197993Y0744424*
X1197869Y07438*
X1197993Y0743176*
X1198347Y0742647*
X1198876Y0742293*
X11995Y0742169*
X1200124Y0742293*
X1200653Y0742647*
X1201007Y0743176*
X1201131Y07438*
X1201007Y0744424*
X1200653Y0744953*
X1200124Y0745307*
X11995Y0745431*
G37*
G36*
X1289035Y0865117D02*
X1287542Y0864921D01*
X128615Y0864344*
X1284955Y0863427*
X1284038Y0862232*
X1283461Y086084*
X1283265Y0859346*
X1283461Y0857853*
X1284038Y0856461*
X1284955Y0855266*
X128615Y0854349*
X1287542Y0853773*
X1289035Y0853576*
X1290529Y0853773*
X1291921Y0854349*
X1293116Y0855266*
X1294033Y0856461*
X1294609Y0857853*
X1294806Y0859346*
X1294609Y086084*
X1294033Y0862232*
X1293116Y0863427*
X1291921Y0864344*
X1290529Y0864921*
X1289035Y0865117*
G37*
G36*
X12725D02*
X1271006Y0864921D01*
X1269615Y0864344*
X1268419Y0863427*
X1267502Y0862232*
X1266926Y086084*
X1266729Y0859346*
X1266926Y0857853*
X1267502Y0856461*
X1268419Y0855266*
X1269615Y0854349*
X1271006Y0853773*
X12725Y0853576*
X1273993Y0853773*
X1275385Y0854349*
X1276581Y0855266*
X1277497Y0856461*
X1278074Y0857853*
X1278271Y0859346*
X1278074Y086084*
X1277497Y0862232*
X1276581Y0863427*
X1275385Y0864344*
X1273993Y0864921*
X12725Y0865117*
G37*
G36*
X1255965D02*
X1254471Y0864921D01*
X1253079Y0864344*
X1251884Y0863427*
X1250967Y0862232*
X1250391Y086084*
X1250194Y0859346*
X1250391Y0857853*
X1250967Y0856461*
X1251884Y0855266*
X1253079Y0854349*
X1254471Y0853773*
X1255965Y0853576*
X1257458Y0853773*
X125885Y0854349*
X1260045Y0855266*
X1260962Y0856461*
X1261539Y0857853*
X1261735Y0859346*
X1261539Y086084*
X1260962Y0862232*
X1260045Y0863427*
X125885Y0864344*
X1257458Y0864921*
X1255965Y0865117*
G37*
G36*
X125Y0847631D02*
X1249376Y0847507D01*
X1248847Y0847153*
X1248493Y0846624*
X1248369Y0846*
X1248493Y0845376*
X1248847Y0844847*
X1249376Y0844493*
X125Y0844369*
X1250624Y0844493*
X1251153Y0844847*
X1251507Y0845376*
X1251631Y0846*
X1251507Y0846624*
X1251153Y0847153*
X1250624Y0847507*
X125Y0847631*
G37*
G36*
X1247Y0844631D02*
X1246376Y0844507D01*
X1245846Y0844153*
X1245493Y0843624*
X1245369Y0843*
X1245493Y0842376*
X1245846Y0841846*
X1246376Y0841493*
X1247Y0841369*
X1247624Y0841493*
X1248153Y0841846*
X1248507Y0842376*
X1248631Y0843*
X1248507Y0843624*
X1248153Y0844153*
X1247624Y0844507*
X1247Y0844631*
G37*
G36*
X1243773Y0841631D02*
X1243149Y0841507D01*
X124262Y0841154*
X1242266Y0840624*
X1242142Y084*
X1242266Y0839376*
X124262Y0838846*
X1243149Y0838493*
X1243773Y0838369*
X1244398Y0838493*
X1244927Y0838846*
X1245281Y0839376*
X1245405Y084*
X1245281Y0840624*
X1244927Y0841154*
X1244398Y0841507*
X1243773Y0841631*
G37*
G36*
X124Y0839131D02*
X1239376Y0839007D01*
X1238846Y0838653*
X1238493Y0838124*
X1238369Y08375*
X1238493Y0836876*
X1238846Y0836347*
X1239376Y0835993*
X124Y0835869*
X1240624Y0835993*
X1241154Y0836347*
X1241507Y0836876*
X1241631Y08375*
X1241507Y0838124*
X1241154Y0838653*
X1240624Y0839007*
X124Y0839131*
G37*
G36*
X12639Y0836131D02*
X1263276Y0836007D01*
X1262747Y0835653*
X1262393Y0835124*
X1262269Y08345*
X1262393Y0833876*
X1262747Y0833346*
X1263276Y0832993*
X12639Y0832869*
X1264524Y0832993*
X1265053Y0833346*
X1265407Y0833876*
X1265531Y08345*
X1265407Y0835124*
X1265053Y0835653*
X1264524Y0836007*
X12639Y0836131*
G37*
G36*
X1234491Y0835139D02*
X1233866Y0835015D01*
X1233337Y0834661*
X1232983Y0834132*
X1232859Y0833508*
X1232983Y0832883*
X1233337Y0832354*
X1233866Y0832*
X1234491Y0831876*
X1235115Y0832*
X1235644Y0832354*
X1235998Y0832883*
X1236122Y0833508*
X1235998Y0834132*
X1235644Y0834661*
X1235115Y0835015*
X1234491Y0835139*
G37*
G36*
X12435Y0831131D02*
X1242876Y0831007D01*
X1242346Y0830653*
X1241993Y0830124*
X1241869Y08295*
X1241993Y0828876*
X1242346Y0828347*
X1242876Y0827993*
X12435Y0827869*
X1244124Y0827993*
X1244654Y0828347*
X1245007Y0828876*
X1245131Y08295*
X1245007Y0830124*
X1244654Y0830653*
X1244124Y0831007*
X12435Y0831131*
G37*
G36*
X12325Y0828631D02*
X1231876Y0828507D01*
X1231347Y0828154*
X1230993Y0827624*
X1230869Y0827*
X1230993Y0826376*
X1231347Y0825846*
X1231876Y0825493*
X12325Y0825369*
X1233124Y0825493*
X1233654Y0825846*
X1234007Y0826376*
X1234131Y0827*
X1234007Y0827624*
X1233654Y0828154*
X1233124Y0828507*
X12325Y0828631*
G37*
G36*
X12467Y0825131D02*
X1246076Y0825007D01*
X1245547Y0824654*
X1245193Y0824124*
X1245069Y08235*
X1245193Y0822876*
X1245547Y0822346*
X1246076Y0821993*
X12467Y0821869*
X1247324Y0821993*
X1247853Y0822346*
X1248207Y0822876*
X1248331Y08235*
X1248207Y0824124*
X1247853Y0824654*
X1247324Y0825007*
X12467Y0825131*
G37*
G36*
X1227257Y0824631D02*
X1226633Y0824507D01*
X1226104Y0824154*
X122575Y0823624*
X1225626Y0823*
X122575Y0822376*
X1226104Y0821846*
X1226633Y0821493*
X1227257Y0821369*
X1227882Y0821493*
X1228411Y0821846*
X1228765Y0822376*
X1228889Y0823*
X1228765Y0823624*
X1228411Y0824154*
X1227882Y0824507*
X1227257Y0824631*
G37*
G36*
X1229957Y0821931D02*
X1229333Y0821807D01*
X1228804Y0821453*
X122845Y0820924*
X1228326Y08203*
X122845Y0819676*
X1228804Y0819147*
X1229333Y0818793*
X1229957Y0818669*
X1230582Y0818793*
X1231111Y0819147*
X1231464Y0819676*
X1231589Y08203*
X1231464Y0820924*
X1231111Y0821453*
X1230582Y0821807*
X1229957Y0821931*
G37*
G36*
X1243Y0821131D02*
X1242376Y0821007D01*
X1241846Y0820654*
X1241493Y0820124*
X1241369Y08195*
X1241493Y0818876*
X1241846Y0818347*
X1242376Y0817993*
X1243Y0817869*
X1243624Y0817993*
X1244153Y0818347*
X1244507Y0818876*
X1244631Y08195*
X1244507Y0820124*
X1244153Y0820654*
X1243624Y0821007*
X1243Y0821131*
G37*
G36*
X1233Y0817131D02*
X1232376Y0817007D01*
X1231847Y0816654*
X1231493Y0816124*
X1231369Y08155*
X1231493Y0814876*
X1231847Y0814347*
X1232376Y0813993*
X1233Y0813869*
X1233624Y0813993*
X1234153Y0814347*
X1234507Y0814876*
X1234631Y08155*
X1234507Y0816124*
X1234153Y0816654*
X1233624Y0817007*
X1233Y0817131*
G37*
G36*
X126378Y0815017D02*
X1263155Y0814893D01*
X1262626Y0814539*
X1262272Y081401*
X1262148Y0813386*
X1262272Y0812761*
X1262626Y0812232*
X1263155Y0811879*
X126378Y0811755*
X1264404Y0811879*
X1264933Y0812232*
X1265287Y0812761*
X1265411Y0813386*
X1265287Y081401*
X1264933Y0814539*
X1264404Y0814893*
X126378Y0815017*
G37*
G36*
X12295Y0814131D02*
X1228876Y0814007D01*
X1228347Y0813653*
X1227993Y0813124*
X1227869Y08125*
X1227993Y0811876*
X1228347Y0811347*
X1228876Y0810993*
X12295Y0810869*
X1230124Y0810993*
X1230653Y0811347*
X1231007Y0811876*
X1231131Y08125*
X1231007Y0813124*
X1230653Y0813653*
X1230124Y0814007*
X12295Y0814131*
G37*
G36*
X12617Y0805231D02*
X1261076Y0805107D01*
X1260546Y0804753*
X1260193Y0804224*
X1260069Y08036*
X1260193Y0802976*
X1260546Y0802446*
X1261076Y0802093*
X12617Y0801969*
X1262324Y0802093*
X1262854Y0802446*
X1263207Y0802976*
X1263331Y08036*
X1263207Y0804224*
X1262854Y0804753*
X1262324Y0805107*
X12617Y0805231*
G37*
G36*
X12447Y0802931D02*
X1244076Y0802807D01*
X1243546Y0802454*
X1243193Y0801924*
X1243069Y08013*
X1243193Y0800676*
X1243546Y0800146*
X1244076Y0799793*
X12447Y0799669*
X1245324Y0799793*
X1245854Y0800146*
X1246207Y0800676*
X1246331Y08013*
X1246207Y0801924*
X1245854Y0802454*
X1245324Y0802807*
X12447Y0802931*
G37*
G36*
X123622Y079297D02*
X1235596Y0792846D01*
X1235067Y0792492*
X1234713Y0791963*
X1234589Y0791339*
X1234713Y0790714*
X1235067Y0790185*
X1235596Y0789831*
X123622Y0789707*
X1236845Y0789831*
X1237374Y0790185*
X1237728Y0790714*
X1237852Y0791339*
X1237728Y0791963*
X1237374Y0792492*
X1236845Y0792846*
X123622Y079297*
G37*
G36*
X12389Y0767731D02*
X1238276Y0767607D01*
X1237747Y0767253*
X1237393Y0766724*
X1237269Y07661*
X1237393Y0765476*
X1237747Y0764947*
X1238276Y0764593*
X12389Y0764469*
X1239524Y0764593*
X1240053Y0764947*
X1240407Y0765476*
X1240531Y07661*
X1240407Y0766724*
X1240053Y0767253*
X1239524Y0767607*
X12389Y0767731*
G37*
G36*
X12388Y0763031D02*
X1238176Y0762907D01*
X1237646Y0762554*
X1237293Y0762024*
X1237169Y07614*
X1237293Y0760776*
X1237646Y0760247*
X1238176Y0759893*
X12388Y0759769*
X1239424Y0759893*
X1239954Y0760247*
X1240307Y0760776*
X1240431Y07614*
X1240307Y0762024*
X1239954Y0762554*
X1239424Y0762907*
X12388Y0763031*
G37*
G36*
X12387Y0757631D02*
X1238076Y0757507D01*
X1237547Y0757154*
X1237193Y0756624*
X1237069Y0756*
X1237193Y0755376*
X1237547Y0754846*
X1238076Y0754493*
X12387Y0754369*
X1239324Y0754493*
X1239853Y0754846*
X1240207Y0755376*
X1240331Y0756*
X1240207Y0756624*
X1239853Y0757154*
X1239324Y0757507*
X12387Y0757631*
G37*
G36*
X12388Y0752131D02*
X1238176Y0752007D01*
X1237646Y0751653*
X1237293Y0751124*
X1237169Y07505*
X1237293Y0749876*
X1237646Y0749346*
X1238176Y0748993*
X12388Y0748869*
X1239424Y0748993*
X1239954Y0749346*
X1240307Y0749876*
X1240431Y07505*
X1240307Y0751124*
X1239954Y0751653*
X1239424Y0752007*
X12388Y0752131*
G37*
G36*
X12389Y0747331D02*
X1238276Y0747207D01*
X1237747Y0746853*
X1237393Y0746324*
X1237269Y07457*
X1237393Y0745076*
X1237747Y0744547*
X1238276Y0744193*
X12389Y0744069*
X1239524Y0744193*
X1240053Y0744547*
X1240407Y0745076*
X1240531Y07457*
X1240407Y0746324*
X1240053Y0746853*
X1239524Y0747207*
X12389Y0747331*
G37*
G36*
X12598Y0719631D02*
X1259176Y0719507D01*
X1258646Y0719153*
X1258293Y0718624*
X1258169Y0718*
X1258293Y0717376*
X1258646Y0716847*
X1259176Y0716493*
X12598Y0716369*
X1260424Y0716493*
X1260954Y0716847*
X1261307Y0717376*
X1261431Y0718*
X1261307Y0718624*
X1260954Y0719153*
X1260424Y0719507*
X12598Y0719631*
G37*
G36*
X1294Y0711531D02*
X1293376Y0711407D01*
X1292846Y0711054*
X1292493Y0710524*
X1292369Y07099*
X1292493Y0709276*
X1292846Y0708746*
X1293376Y0708393*
X1294Y0708269*
X1294624Y0708393*
X1295154Y0708746*
X1295507Y0709276*
X1295631Y07099*
X1295507Y0710524*
X1295154Y0711054*
X1294624Y0711407*
X1294Y0711531*
G37*
G36*
X13042Y0697731D02*
X1303576Y0697607D01*
X1303047Y0697254*
X1302693Y0696724*
X1302569Y06961*
X1302693Y0695476*
X1303047Y0694946*
X1303576Y0694593*
X13042Y0694469*
X1304824Y0694593*
X1305354Y0694946*
X1305707Y0695476*
X1305831Y06961*
X1305707Y0696724*
X1305354Y0697254*
X1304824Y0697607*
X13042Y0697731*
G37*
%LNgrandmaster-3*%
%LPD*%
G54D10*
X0900866Y05115D02*
X0901Y0511634D01*
X086937Y05115D02*
X08695Y051163D01*
X07887Y05739D02*
Y0652D01*
X0788746Y0652046*
X07887Y05739D02*
X0818189Y0544411D01*
X0833937Y05115D02*
X0834Y0511563D01*
X0818189Y05115D02*
Y0544411D01*
X0778819Y051345D02*
Y05359D01*
X08975Y0805D02*
X0898D01*
X09045Y07985*
X0907*
X1004Y08669D02*
Y08705D01*
X09935Y0881D02*
X1004Y08705D01*
X0982Y0881D02*
X09935D01*
X08406Y08127D02*
X08414D01*
X0840452Y0812552D02*
X08406Y08127D01*
X08325Y0812552D02*
X0840452D01*
X085Y0809317D02*
Y0812552D01*
X08495Y0808817D02*
X085Y0809317D01*
X08495Y08086D02*
Y0808817D01*
X08325Y0820426D02*
X0833126Y08198D01*
X0841*
X0858Y08289D02*
Y08291D01*
X08581Y08292*
X085Y08283D02*
X08574D01*
X0858Y08289*
X085Y0820426D02*
X0858174D01*
X08582Y08204*
G54D14*
X08702Y07936D02*
Y0800707D01*
Y07936D02*
X08714Y07924D01*
X0838843Y07948D02*
Y0795391D01*
X0840607Y0797154D02*
X0841198D01*
X0842443Y07984*
X0838843Y0795391D02*
X0840607Y0797154D01*
X0842443Y07984D02*
X08464D01*
X08325Y08283D02*
X08388D01*
X08404Y08299*
X08623Y07881D02*
Y0797557D01*
X08622Y0788D02*
X08623Y07881D01*
X0837593Y07858D02*
X0837672D01*
X0838431Y078504*
Y0784961D02*
Y078504D01*
Y0784961D02*
X08406Y0782793D01*
Y07796D02*
Y0782793D01*
G54D22*
X0896929Y05115D02*
D01*
X089694Y0511512*
X0896951Y0511525*
X089696Y0511539*
X0896969Y0511553*
X0896977Y0511568*
X0896983Y0511584*
X0896989Y05116*
X0896993Y0511616*
X0896996Y0511633*
X0896998Y0511649*
X0896999Y0511666*
X0897Y0511671*
X0834Y0533307D02*
D01*
X0833989Y0533296*
X083398Y0533284*
X0833971Y0533272*
X0833963Y0533259*
X0833957Y0533245*
X0833951Y0533232*
X0833946Y0533217*
X0833942Y0533203*
X0833939Y0533188*
X0833937Y0533173*
X0833937Y0533158*
Y0533155*
X0838Y0533307D02*
D01*
X0837979Y0533285*
X083796Y0533261*
X0837943Y0533237*
X0837927Y0533211*
X0837914Y0533184*
X0837902Y0533157*
X0837892Y0533128*
X0837885Y0533099*
X0837879Y053307*
X0837875Y053304*
X0837874Y053301*
X0837874Y0533003*
X0845748Y05115D02*
D01*
X0845772Y0511526*
X0845795Y0511554*
X0845816Y0511584*
X0845834Y0511615*
X0845851Y0511647*
X0845865Y0511681*
X0845877Y0511715*
X0845886Y051175*
X0845893Y0511785*
X0845898Y0511821*
X0845899Y0511857*
X08459Y0511867*
X08502Y0533307D02*
D01*
X0850116Y0533217*
X0850039Y0533121*
X0849968Y0533021*
X0849905Y0532916*
X0849849Y0532806*
X0849801Y0532693*
X0849761Y0532577*
X084973Y0532459*
X0849706Y0532338*
X0849691Y0532217*
X0849685Y0532094*
X0849685Y0532064*
X0865433Y05115D02*
D01*
X0865443Y0511511*
X0865453Y0511524*
X0865463Y0511537*
X0865471Y051155*
X0865478Y0511565*
X0865484Y0511579*
X086549Y0511595*
X0865494Y051161*
X0865497Y0511626*
X0865499Y0511642*
X08655Y0511658*
Y0511662*
X0881181Y053287D02*
D01*
X0881179Y0532913*
X0881174Y0532956*
X0881167Y0532998*
X0881157Y053304*
X0881143Y0533081*
X0881127Y0533121*
X0881108Y053316*
X0881087Y0533197*
X0881062Y0533233*
X0881036Y0533267*
X0881007Y0533299*
X0881Y0533307*
X08845Y0512992D02*
D01*
X0884505Y0512844*
X088452Y0512698*
X0884546Y0512553*
X0884581Y051241*
X0884627Y051227*
X0884682Y0512133*
X0884746Y0512001*
X088482Y0511873*
X0884902Y0511751*
X0884993Y0511635*
X0885092Y0511526*
X0885116Y0511502*
D01*
X0885116Y0511501*
X0885116Y0511501*
X0885117Y05115*
X0885117Y05115*
X0885118Y05115*
X0897Y0533307D02*
D01*
X0896988Y0533294*
X0896977Y0533281*
X0896968Y0533267*
X0896959Y0533253*
X0896951Y0533238*
X0896945Y0533222*
X0896939Y0533206*
X0896935Y053319*
X0896932Y0533173*
X089693Y0533157*
X0896929Y053314*
X0896929Y0533136*
X0901Y0533307D02*
D01*
X0900978Y0533283*
X0900958Y0533258*
X0900939Y0533232*
X0900923Y0533205*
X0900909Y0533177*
X0900896Y0533147*
X0900886Y0533117*
X0900877Y0533086*
X0900871Y0533055*
X0900867Y0533023*
X0900866Y0532991*
X0900866Y0532984*
X08369Y0539349D02*
D01*
X0836909Y0539086*
X0836936Y0538826*
X0836982Y0538568*
X0837045Y0538313*
X0837126Y0538064*
X0837224Y0537821*
X0837339Y0537585*
X083747Y0537358*
X0837617Y0537141*
X0837778Y0536934*
X0837954Y0536739*
X0838Y0536693*
X0834D02*
D01*
X0834081Y053678*
X0834156Y0536872*
X0834224Y053697*
X0834285Y0537072*
X083434Y0537178*
X0834386Y0537288*
X0834425Y05374*
X0834456Y0537516*
X0834478Y0537632*
X0834493Y0537751*
X0834499Y053787*
X08345Y05379*
X0846Y05402D02*
D01*
X0845983Y0540182*
X0845968Y0540164*
X0845955Y0540144*
X0845942Y0540124*
X0845932Y0540103*
X0845922Y0540081*
X0845915Y0540058*
X0845908Y0540035*
X0845904Y0540012*
X0845901Y0539988*
X08459Y0539964*
X08459Y0539959*
X086937Y05115D02*
D01*
X0869391Y0511522*
X086941Y0511546*
X0869428Y0511572*
X0869444Y0511598*
X0869458Y0511626*
X086947Y0511654*
X086948Y0511684*
X0869488Y0511714*
X0869494Y0511744*
X0869498Y0511775*
X0869499Y0511806*
X08695Y0511814*
X08459Y0511867D02*
Y0533307D01*
X0837874Y05115D02*
Y0533003D01*
X0833937Y05115D02*
Y0533155D01*
X0849685Y05115D02*
Y0532064D01*
X08655Y0511662D02*
Y0533307D01*
X0881181Y05115D02*
Y053287D01*
X08845Y0512992D02*
Y0533307D01*
X0896929Y05115D02*
Y0533136D01*
X0900866Y05115D02*
Y0532984D01*
X08845Y0536693D02*
Y05399D01*
X0881Y0536693D02*
Y05399D01*
X0901Y0536693D02*
Y05397D01*
X08369Y0539349D02*
Y05434D01*
X08345Y05379D02*
Y05434D01*
X08459Y0536693D02*
Y0539959D01*
X0897Y0536693D02*
Y05398D01*
X08695Y0536693D02*
Y054D01*
X08655Y0536693D02*
Y05401D01*
X08695Y0511814D02*
Y0533307D01*
X08502Y0536693D02*
Y05401D01*
G54D53*
X0908661Y0514173D03*
X0786614D03*
X0782677D03*
X0814173D03*
X0810236D03*
X0869291D03*
X0900787D03*
X089685D03*
X0885039D03*
X0865354D03*
X0881102D03*
X0849606D03*
X0845669D03*
X0837795D03*
X0833858D03*
X081811D03*
X0794488D03*
X0798425D03*
X0802362D03*
X0806299D03*
X085748D03*
X0841732D03*
X0829921D03*
X0877165D03*
X0892913D03*
X0873228D03*
X0904724D03*
X0888976D03*
X0861417D03*
X0853543D03*
X0790551D03*
G54D54*
X077874Y0516123D03*
G54D64*
X08623Y0804643D03*
Y0797557D03*
G54D66*
X0834Y0536693D03*
Y0533307D03*
X0838D03*
Y0536693D03*
X08459D03*
Y0533307D03*
X08502D03*
Y0536693D03*
X08655Y0533307D03*
Y0536693D03*
X08695Y0533307D03*
Y0536693D03*
X0881Y0533307D03*
Y0536693D03*
X08845D03*
Y0533307D03*
X0897D03*
Y0536693D03*
X0901Y0533307D03*
Y0536693D03*
X08702Y0804093D03*
Y0800707D03*
G54D71*
X0831757Y07948D03*
X0838843D03*
G54D72*
X0834207Y07858D03*
X0837593D03*
G54D76*
X085Y0804678D03*
Y0820426D03*
Y0812552D03*
Y08283D03*
X08325Y0804678D03*
Y0812552D03*
Y0820426D03*
Y08283D03*
G54D140*
X0609Y0601D03*
Y0581D03*
X0629D03*
Y0601D03*
X0609Y07585D03*
Y07385D03*
X0629D03*
Y07585D03*
X0609Y0706D03*
Y0686D03*
X0629D03*
Y0706D03*
X0609Y06535D03*
Y06335D03*
X0629D03*
Y06535D03*
G54D147*
X0904848Y0511545D02*
Y0514297D01*
X0904946Y0514395*
X0904724Y0514173D02*
X0904848Y0514297D01*
X0904946Y0523533D02*
X0906118Y0524705D01*
X090876*
X0904946Y0514395D02*
Y0523533D01*
X0892592Y05119D02*
Y0514495D01*
X0892913Y0514173*
X0892513Y0514573D02*
X0892592Y0514495D01*
X0888902Y0523992D02*
X0891342D01*
X0892513Y052282*
Y0514573D02*
Y052282D01*
X0887205Y0525689D02*
X0888902Y0523992D01*
Y0514247D02*
Y0523992D01*
Y0514247D02*
X0888976Y0514173D01*
X0873228Y0524419D02*
X08744Y0525591D01*
X0878937*
X0873228Y0514173D02*
Y0524419D01*
X0877289Y0523942D02*
X0878937Y0525591D01*
X0877289Y0514297D02*
Y0523942D01*
X0877165Y0514173D02*
X0877289Y0514297D01*
X0861496Y05115D02*
Y0523977D01*
X0862703Y0525184*
X0841811Y052311D02*
X0843701Y0525D01*
X0841811Y05115D02*
Y052311D01*
X08105Y0529264D02*
X081413Y0525634D01*
X0810236Y0525984D02*
D01*
Y0514173D02*
Y0525984D01*
X081413Y0511622D02*
Y0525634D01*
X0786693Y05115D02*
Y0524699D01*
X0782756Y05115D02*
Y0526148D01*
X0892592Y05119D02*
X0892992Y05115D01*
X0853622D02*
Y0524878D01*
X0818077Y0511613D02*
X0818189Y05115D01*
X081413Y0511622D02*
X0814252Y05115D01*
X0784Y0527392D02*
X0786693Y0524699D01*
X083Y05115D02*
Y0525D01*
X0782756Y0526148D02*
X0784Y0527392D01*
X0904803Y05115D02*
X0904848Y0511545D01*
X079063Y05115D02*
Y052487D01*
X0988Y05775D02*
X1032988Y0622488D01*
X11985Y0856D02*
X12415Y0813D01*
X0921Y0881D02*
X09215Y08815D01*
X09209Y08809D02*
X0921Y0881D01*
X0871257Y0879001D02*
X0877467D01*
X0871001D02*
X0871257D01*
X1049382Y0779382D02*
X1198382D01*
X11985Y07795*
X09562Y07037D02*
Y07062D01*
X08623Y0804643D02*
X086285Y0804093D01*
X0862265Y0804678D02*
X08623Y0804643D01*
X085Y0804678D02*
X0862265D01*
X086285Y0804093D02*
X08702D01*
X09562Y0701477D02*
Y07037D01*
X09571Y0688217D02*
Y0700577D01*
Y0688217D02*
X0963Y0682317D01*
X09562Y0701477D02*
X09571Y0700577D01*
X0955Y0674317D02*
X0963Y0682317D01*
X0898823Y08815D02*
X0899423Y08809D01*
X09209*
X0877467Y0879001D02*
X0879966Y08815D01*
X09525D02*
X0953Y0881D01*
X091525Y0748427D02*
X09359Y0727777D01*
Y07256D02*
X0954Y07075D01*
X09359Y07256D02*
Y0727777D01*
X091525Y0748427D02*
Y081825D01*
X0871Y0879D02*
X0871001Y0879001D01*
X0813Y08615D02*
X0833304D01*
X0850804Y0879*
X0871*
X11265Y08515D02*
X11985Y07795D01*
X12275Y07505*
X0959073Y0606427D02*
Y064367D01*
X0955Y0647743D02*
X0959073Y064367D01*
X0955Y0647743D02*
Y0674317D01*
X0959073Y0606427D02*
X0988Y05775D01*
X08765Y0857D02*
X091525Y081825D01*
X10035Y0857D02*
X10245Y0878D01*
X08765Y0857D02*
X10035D01*
X1032988Y0622488D02*
X1239488D01*
X12835Y06665*
X1272Y0634D02*
X12995Y06615D01*
Y0755*
X12415Y0813D02*
X12995Y0755D01*
X12415Y07185D02*
Y0813D01*
G54D152*
X06285Y05373D03*
X13206Y05701D03*
X06294Y09156D03*
X13206Y09168D03*
G54D153*
X09775Y0913D03*
X0994823D03*
G54D154*
X08985Y0909004D03*
X09285D03*
G54D155*
X1028878Y0759928D03*
X1017067D03*
X1005256D03*
X0996988Y0589456D03*
Y0749298D03*
X1156831D03*
Y0669377D03*
Y0589456D03*
G54D156*
X117122Y0896D03*
Y091411D03*
X1255965Y0881D03*
Y0859346D03*
X12725Y0881D03*
Y0859346D03*
X1289035D03*
Y0881D03*
G54D157*
X1211Y0882378D03*
G54D158*
X1211Y0906D03*
G54D159*
X1192496Y0894189D03*
G54D160*
X0619Y0591D03*
Y07485D03*
Y0696D03*
Y06435D03*
G54D161*
X0898069Y0744247D03*
X089807Y0596253D03*
X081933D03*
X0768699Y0710117D03*
Y0631377D03*
X0819329Y0744247D03*
X095619Y0631373D03*
Y0710113D03*
G54D162*
X0803Y09156D03*
Y09056D03*
X07429Y09164D03*
Y09064D03*
G54D163*
X0803Y09256D03*
X07429Y09264D03*
G54D164*
X1255965Y090974D03*
X1289035D03*
G54D165*
X090876Y0524705D03*
X0894587Y0525591D03*
X0853622Y0524878D03*
X0843701Y0525D03*
X08422Y05285D03*
X08398D03*
X0806693Y0525984D03*
Y0529134D03*
X0810236D03*
X0814173D03*
X0810236Y0525984D03*
X0814173D03*
X079063Y052487D03*
X0782283Y0525984D03*
X0784252D03*
X0786221D03*
X0782283Y0529134D03*
X0784252D03*
X0786221D03*
X0876Y0529D03*
X08736D03*
X08898Y05287D03*
X08025Y0525D03*
X08595Y05288D03*
X0862703Y0525184D03*
X0788746Y0652046D03*
X0878937Y0525591D03*
X083Y0525D03*
X08566Y05289D03*
X08922Y05287D03*
X0887205Y0525689D03*
X07788Y05359D03*
X0891732Y0814961D03*
X0885827D03*
X0883071D03*
X0888976D03*
X0891732Y0811811D03*
X0885827D03*
X0883071D03*
X0888976D03*
X0891732Y081811D03*
X0885827D03*
X0883071D03*
X0888976D03*
Y082126D03*
X0883071D03*
X0885827D03*
X0891732D03*
X1224409Y0791339D03*
X126378Y0813386D03*
X1125716Y0909284D03*
X1033Y07729D03*
X1049382Y0779382D03*
X082219Y075881D03*
X082425Y076175D03*
X0826219Y0746781D03*
X09562Y07062D03*
X0931933Y0683D03*
X0940462Y06809D03*
X0942941Y0687488D03*
X0996Y06556D03*
X0781294Y0667794D03*
X0787009Y0681574D03*
X0755836Y0707164D03*
X11985Y08556D03*
X09592Y08142D03*
Y07896D03*
X08975Y0805D03*
X0907Y07985D03*
X1004Y08669D03*
X0982Y0881D03*
X07779Y09331D03*
X09581Y06666D03*
X08321Y07219D03*
X11568Y07218D03*
X08774Y07572D03*
X07712Y06993D03*
X08693Y07293D03*
X08685Y06485D03*
X10055Y06515D03*
X08887Y08382D03*
X0838Y08485D03*
X08375Y06945D03*
X09795Y06844D03*
X08505Y05941D03*
X08656Y06096D03*
X09821Y08766D03*
X12325Y0827D03*
X09735Y08265D03*
X0976402Y0667004D03*
X08314Y0759D03*
X07662Y06796D03*
X08774Y06098D03*
X09386Y09226D03*
X10263Y08139D03*
X0971Y07D03*
X09401Y0671759D03*
X0849Y0724D03*
X11625D03*
X08615Y07465D03*
X08617Y06774D03*
X10055Y068D03*
X07705Y06599D03*
X1085Y08D03*
X12295Y08125D03*
X0993D03*
X09915Y0654D03*
X08716Y08164D03*
X08717Y08329D03*
X09048Y08159D03*
X0813Y08742D03*
X0918742Y06718D03*
X09188Y07974D03*
X08414Y08127D03*
X08479Y07417D03*
X08401Y06093D03*
X1012Y0852D03*
X08485Y07665D03*
X0903536Y0821364D03*
X10199Y08139D03*
X09585Y06518D03*
X08676Y07572D03*
X07662Y06403D03*
X08137Y07757D03*
X10125Y06755D03*
X08595Y06738D03*
X0859Y0744D03*
X12617Y08036D03*
X10143Y08139D03*
X08694Y05952D03*
X08245Y0854D03*
X0829Y0692D03*
X09545Y06895D03*
X10055Y07726D03*
X08485Y077D03*
X08715Y08525D03*
X08302Y05938D03*
X08862Y07301D03*
X07666Y06895D03*
X08845Y05399D03*
X0881D03*
X0888285Y0583251D03*
X08852Y05824D03*
X07239Y07004D03*
X0971Y06925D03*
X09404Y06577D03*
X0857Y07285D03*
Y06794D03*
X09935Y0682D03*
X07712Y06698D03*
X08807Y07907D03*
X08907D03*
X10122Y0669D03*
X08303Y06097D03*
X10059Y08139D03*
X08665Y08505D03*
X10225Y07729D03*
X08714Y07924D03*
X08395Y07416D03*
X09723Y06422D03*
X08577Y07573D03*
X07662Y06501D03*
X09545Y06995D03*
X08961Y08415D03*
X12447Y08013D03*
X07682Y09083D03*
X09633Y0564D03*
X0825Y08265D03*
X09365Y08277D03*
X09359Y08054D03*
X08774Y07433D03*
X07665Y06993D03*
X1003Y08788D03*
X12467Y08235D03*
X10324Y08139D03*
X10468D03*
X09545Y06845D03*
X09397Y06465D03*
X08566Y07416D03*
X1003Y0741D03*
X07707Y06403D03*
X07709Y06796D03*
X07548Y09233D03*
X09188Y08218D03*
X07717Y0933D03*
X08244Y07283D03*
X08924Y05957D03*
X0971Y0677D03*
X0854Y06759D03*
X08625Y0841D03*
X08466Y0746D03*
X07661Y06599D03*
X08892Y06099D03*
X09545Y06945D03*
X09268Y06809D03*
X09265Y0861D03*
X1066D03*
X09959Y06675D03*
X09951Y07728D03*
X08601Y05938D03*
X1227257Y0823D03*
X09797Y08239D03*
X09794Y06695D03*
X08464Y07984D03*
X08676Y07315D03*
X08597Y06095D03*
X07252Y07486D03*
X09709Y06717D03*
X0954Y06417D03*
X08872Y0757D03*
X07709Y06501D03*
X07712Y06894D03*
X08875Y07903D03*
X09987Y06715D03*
X08404Y08299D03*
X10105Y08139D03*
X12639Y08345D03*
X0832Y08365D03*
X08622Y0788D03*
X08879Y09225D03*
X09361Y07892D03*
X084Y07583D03*
X07661Y06698D03*
X08833Y06099D03*
X08753Y07906D03*
X08249Y08745D03*
X08406Y07796D03*
X08572Y07312D03*
X08499Y06094D03*
X0774Y09114D03*
X08561Y09287D03*
X0745Y08151D03*
X07431Y08561D03*
X07576Y09129D03*
X07894Y09022D03*
X08235Y09021D03*
X08281Y09221D03*
X09871Y08113D03*
X09482Y08107D03*
X08812Y07605D03*
X09614Y07591D03*
X09613Y0849D03*
X09482Y08301D03*
X0953302Y0832298D03*
X09335Y08D03*
X09735Y08346D03*
X09644Y08297D03*
X09385Y08451D03*
X09427Y08461D03*
X09349Y08452D03*
X09708Y08076D03*
X08425Y0855D03*
X0857Y0849D03*
X07884Y06697D03*
X09215Y0666528D03*
X0879Y0862D03*
X0958Y06715D03*
X0901Y054D03*
X11724Y0856D03*
X11667Y0855D03*
X08405Y05941D03*
X09594Y05686D03*
X08469Y05941D03*
X08715Y06097D03*
X12619Y06376D03*
X12539Y06535D03*
X12593Y06616D03*
Y06676D03*
Y06726D03*
X12592Y06781D03*
X12676Y06832D03*
X1269Y06885D03*
X13042Y06961D03*
X1294Y07099D03*
X12598Y0718D03*
X12386Y07115D03*
X12039Y07175D03*
X11995Y07438D03*
X12265Y07395D03*
X12389Y07457D03*
X12388Y07505D03*
X12387Y0756D03*
X12388Y07614D03*
X12389Y07661D03*
X123622Y0791339D03*
X10901Y09207D03*
X10378Y0921D03*
X09768Y09027D03*
X10076Y08896D03*
X10185Y08888D03*
X10422Y08139D03*
X09321Y08305D03*
X0909Y07916D03*
X09023Y07972D03*
X09009Y07901D03*
X08851Y08791D03*
X08715Y08733D03*
X09522Y08664D03*
X0926Y08792D03*
X07233Y06476D03*
X07247Y05946D03*
X06645Y05794D03*
X06646Y06032D03*
X06645Y06318D03*
X06644Y06555D03*
X06645Y06843D03*
Y07077D03*
Y07369D03*
X0664412Y0759783D03*
X08717Y07297D03*
X08622Y05978D03*
X08933Y0729D03*
X08734Y05827D03*
X08783Y0579D03*
X08656Y07295D03*
X08658Y05985D03*
X09885Y0657D03*
X084Y07318D03*
X07556Y06323D03*
X08582Y05817D03*
X08794Y07311D03*
X08976Y07291D03*
X08466Y07295D03*
X087657Y0582263D03*
X08822Y05792D03*
X08727Y05947D03*
X09855Y06515D03*
X09395Y0636726D03*
X09289Y06975D03*
X07875Y07075D03*
X09383Y06875D03*
X08692Y05985D03*
X0873525Y0599177D03*
X08911Y07432D03*
X08949Y07625D03*
X08636Y07278D03*
X084Y07287D03*
X088Y05978D03*
X0937Y0639D03*
X08441Y07286D03*
X09243Y06665D03*
X0954Y06445D03*
X08939Y0746D03*
X0761Y07125D03*
X08588Y05979D03*
X0937Y0634D03*
X0771Y0654D03*
X08616Y05817D03*
X09825Y06485D03*
X08885Y07435D03*
X07745Y0713D03*
X0882941Y0599141D03*
X07782Y06301D03*
X0939744Y0641526D03*
X08832Y07267D03*
X0957Y07947D03*
X09221Y08239D03*
X09243Y08297D03*
X08197Y06302D03*
X08196Y08204D03*
X08495Y08086D03*
X08493Y0632D03*
X0841Y08198D03*
X08581Y08292D03*
X08582Y08204D03*
X08516Y07467D03*
X09333Y07267D03*
X09489Y07345D03*
X0841935Y07625D03*
X06995Y0591D03*
X08437Y06441D03*
X06999Y06434D03*
X084Y06971D03*
X07Y0696D03*
X07011Y07485D03*
X08634Y0662D03*
X08657Y06644D03*
X08345Y05434D03*
X08369D03*
X0876532Y0598081D03*
X0897Y05398D03*
X08695Y054D03*
X08655Y05401D03*
X0846Y05402D03*
X08502Y05401D03*
X0957Y0759D03*
X07875Y08605D03*
X07745Y08665D03*
X09415Y0864D03*
X0754Y08625D03*
X0923Y086D03*
X07565D03*
X0953Y0881D03*
X0921D03*
X0871257Y0879001D03*
X0813Y08615D03*
X08075Y089D03*
X08074Y064156D03*
X0805Y0639D03*
Y08875D03*
X0802Y0884D03*
X08019Y063656D03*
X07285Y0926D03*
X07995Y0882D03*
Y0634D03*
X08225Y0851D03*
X0952Y08485D03*
X11265Y08515D03*
X12275Y07505D03*
X0867Y08665D03*
X08765Y0857D03*
X09562Y07037D03*
X0898354Y08755D03*
X0969D03*
X09005Y08835D03*
X0969Y0884D03*
X10245Y0878D03*
X08885Y06565D03*
X0891Y0654D03*
X09985Y06555D03*
X08265Y0651D03*
X10025Y0655D03*
X0871Y06595D03*
X1017Y06605D03*
X1014146Y0662756D03*
X10125Y06655D03*
X09715Y06679D03*
X12835Y06665D03*
X12415Y07185D03*
X1229957Y08203D03*
X1233Y08155D03*
X1074487Y0911987D03*
X0777Y0916D03*
X09495Y0909D03*
X09845Y08155D03*
X0982Y0818D03*
X0979Y08205D03*
X1243Y08195D03*
X1234491Y0833508D03*
X12435Y08295D03*
X09293Y08348D03*
X124Y08375D03*
X1243773Y084D03*
X1247Y0843D03*
X125Y0846D03*
X0946D03*
X0784Y08705D03*
X12285D03*
G54D166*
X0845748Y05115D03*
G54D167*
X0812077Y0527246D03*
X0784203Y0527313D03*
M02*